%FSTAX25Y25*%
%MOIN*%
%SFA1B1*%

%IPPOS*%
%AMD54*
4,1,8,0.010500,-0.010000,0.010500,0.010000,0.000000,0.020400,0.000000,0.020400,-0.010500,0.010000,-0.010500,-0.010000,0.000000,-0.020400,0.000000,-0.020400,0.010500,-0.010000,0.0*
1,1,0.020960,0.000000,-0.010000*
1,1,0.020960,0.000000,0.010000*
1,1,0.020960,0.000000,0.010000*
1,1,0.020960,0.000000,-0.010000*
%
%ADD13C,0.010000*%
%ADD18C,0.005000*%
%ADD22R,0.041340X0.043310*%
%ADD23R,0.039370X0.027560*%
%ADD24R,0.055120X0.055120*%
%ADD25R,0.039370X0.055120*%
%ADD26R,0.086610X0.041340*%
%ADD27R,0.041340X0.039370*%
%ADD28R,0.035430X0.019680*%
%ADD29R,0.077560X0.022440*%
%ADD30R,0.041340X0.025590*%
%ADD31R,0.050000X0.200000*%
%ADD32R,0.070870X0.009840*%
%ADD33R,0.057090X0.037400*%
%ADD34R,0.037400X0.031500*%
%ADD35R,0.037400X0.037400*%
%ADD36R,0.029530X0.033470*%
%ADD37R,0.035430X0.027560*%
%ADD38R,0.023620X0.031500*%
%ADD39R,0.039370X0.028350*%
%ADD40R,0.023620X0.025590*%
%ADD41R,0.028000X0.165000*%
%ADD42R,0.028000X0.126000*%
%ADD43O,0.086610X0.023620*%
%ADD44O,0.074800X0.023620*%
%ADD45R,0.212600X0.114170*%
%ADD46R,0.082870X0.044090*%
%ADD47R,0.009840X0.061020*%
%ADD48R,0.066930X0.053150*%
%ADD49R,0.053150X0.066930*%
%ADD50R,0.061020X0.009840*%
%ADD51R,0.026570X0.009840*%
%ADD52R,0.009840X0.026570*%
%ADD53R,0.019680X0.013780*%
G04~CAMADD=54~8~0.0~0.0~408.8~209.5~104.8~0.0~15~0.0~0.0~0.0~0.0~0~0.0~0.0~0.0~0.0~0~0.0~0.0~0.0~270.0~210.0~409.0*
%ADD54D54*%
%ADD55R,0.020950X0.040880*%
%ADD56R,0.033470X0.039370*%
%ADD57R,0.045280X0.057090*%
%ADD58R,0.037400X0.033470*%
%ADD59R,0.043310X0.041340*%
%ADD60R,0.037400X0.039370*%
%ADD61R,0.057090X0.045280*%
%ADD62R,0.028350X0.039370*%
%ADD108C,0.120000*%
%ADD112C,0.008000*%
%ADD113C,0.020000*%
%ADD114C,0.012000*%
%ADD115R,0.098430X0.127950*%
%ADD116R,0.039370X0.248030*%
%ADD117R,0.110430X0.066930*%
%ADD118R,0.105320X0.067910*%
%ADD119C,0.065980*%
%ADD120C,0.075000*%
%ADD121R,0.059060X0.059060*%
%ADD122C,0.059060*%
%ADD123C,0.021660*%
%ADD124C,0.112000*%
%ADD125C,0.250000*%
%ADD126C,0.016000*%
%ADD127C,0.200000*%
%ADD128C,0.050000*%
%ADD129C,0.032000*%
%LNtimecard-dc-beta-v1-1*%
%LPD*%
G36*
X0668486Y029685D02*
X0680512D01*
Y0270276*
X0639875*
Y0270288*
X0634141*
Y026918*
X0633268Y0268307*
Y0248832*
X0628924*
Y0248622*
X0611614*
X0611092Y02481*
X061063Y0248291*
Y0276942*
X0610938Y0277016*
X061138Y0276673*
X0611485Y0276147*
X0611839Y0275618*
X0612368Y0275265*
X0612992Y027514*
X0613616Y0275265*
X0614146Y0275618*
X0614499Y0276147*
X0614623Y0276772*
X0614622Y0276779*
X0614939Y0277165*
X0633717*
X0634141Y0276981*
Y0276665*
Y027105*
X0639875*
Y027269*
X0644188*
X064446Y0272509*
X0645084Y0272384*
X0645709Y0272509*
X0646238Y0272862*
X0646591Y0273392*
X0646716Y0274016*
X0646591Y027464*
X0646238Y0275169*
X0645709Y0275523*
X0645084Y0275647*
X064446Y0275523*
X0644188Y0275341*
X0640228*
X0639875Y0275695*
Y0276981*
X0640299Y0277165*
X0645079*
X0646063Y027815*
Y029685*
X0661793*
Y0317655*
X0668486*
Y029685*
G37*
G36*
X0694291Y0151181D02*
X0672638Y0129528D01*
X0666339*
Y017874*
X0669127Y0181528*
X0669478Y0181458*
X0670102Y0181583*
X0670374Y0181764*
X0671444*
Y0179121*
X0675879*
Y0184646*
X0676877*
Y0179121*
X0681312*
Y0184646*
X0687096*
X0687484Y0184375*
Y0178838*
X0691918*
Y0184375*
X0692306Y0184646*
X0694291*
Y0151181*
G37*
G36*
X0626476Y0140354D02*
X0593996D01*
Y0147047*
X0626476*
Y0140354*
G37*
G36*
X0679191Y0117695D02*
X0679732D01*
Y0117641*
X0680002*
Y0117587*
X0680219*
Y0117533*
X0680327*
Y0117479*
X0680489*
Y0117425*
X0680597*
Y0117371*
X0680759*
Y0117317*
X0680813*
Y0117263*
X0680922*
Y0117209*
X068103*
Y0117155*
X0681084*
Y0117101*
X0681192*
Y0117047*
X0681246*
Y0116993*
X0681354*
Y0116939*
X0681408*
Y0116885*
X0681462*
Y0116831*
X0681516*
Y0116776*
X068157*
Y0116722*
X0681624*
Y0116668*
X0681678*
Y0116614*
X0681732*
Y011656*
X0681786*
Y0116506*
X0681841*
Y0116452*
X0681895*
Y0116398*
X0681949*
Y0116344*
Y011629*
X0682003*
Y0116236*
X0682057*
Y0116182*
Y0116128*
X0682111*
Y0116074*
X0682165*
Y011602*
Y0115965*
X0682219*
Y0115911*
Y0115857*
X0682273*
Y0115803*
X0682327*
Y0115749*
Y0115695*
X0682381*
Y0115641*
Y0115587*
Y0115533*
X0682435*
Y0115479*
Y0115425*
X0682489*
Y0115371*
Y0115317*
Y0115263*
X0682543*
Y0115209*
Y0115155*
Y0115101*
Y0115047*
X0682597*
Y0114992*
Y0114938*
Y0114884*
Y011483*
X0682652*
Y0114776*
Y0114722*
Y0114668*
Y0114614*
Y011456*
Y0114506*
Y0114452*
Y0114398*
Y0114344*
Y011429*
X0682705*
Y0114235*
Y0114181*
Y0114127*
Y0114073*
X0682652*
Y0114019*
Y0113965*
Y0113911*
Y0113857*
Y0113803*
Y0113749*
Y0113695*
Y0113641*
Y0113587*
X0682597*
Y0113533*
Y0113479*
Y0113425*
Y0113371*
Y0113317*
X0682543*
Y0113262*
Y0113208*
Y0113154*
X0682489*
Y01131*
Y0113046*
Y0112992*
X0682435*
Y0112938*
Y0112884*
Y011283*
X0682381*
Y0112776*
Y0112722*
X0682327*
Y0112668*
Y0112614*
X0682273*
Y011256*
Y0112505*
X0682219*
Y0112452*
Y0112397*
X0682165*
Y0112343*
Y0112289*
X0682111*
Y0112235*
X0682057*
Y0112181*
Y0112127*
X0682003*
Y0112073*
X0681949*
Y0112019*
X0681895*
Y0111965*
Y0111911*
X0681841*
Y0111857*
X0681786*
Y0111803*
X0681732*
Y0111749*
X0681678*
Y0111695*
X0681624*
Y0111641*
X068157*
Y0111586*
X0681516*
Y0111532*
X0681462*
Y0111478*
X0681354*
Y0111424*
X06813*
Y011137*
X0681246*
Y0111316*
X0681192*
Y0111262*
X0681084*
Y0111208*
X068103*
Y0111154*
X0680922*
Y01111*
X0680813*
Y0111046*
X0680705*
Y0110992*
X0680597*
Y0110938*
X0680489*
Y0110884*
X0680327*
Y011083*
X0680165*
Y0110776*
X0679948*
Y0110722*
X0679678*
Y0110668*
X0674434*
Y0110722*
X0674164*
Y0110776*
X0674002*
Y011083*
X0673839*
Y0110884*
X0673677*
Y0110938*
X0673569*
Y0110992*
X0673407*
Y0111046*
X0673353*
Y01111*
X0673245*
Y0111154*
X0673137*
Y0111208*
X0673082*
Y0111262*
X0672974*
Y0111316*
X067292*
Y011137*
X0672812*
Y0111424*
X0672758*
Y0111478*
X0672704*
Y0111532*
X067265*
Y0111586*
X0672596*
Y0111641*
X0672542*
Y0111695*
X0672488*
Y0111749*
X0672434*
Y0111803*
X067238*
Y0111857*
X0672326*
Y0111911*
X0672272*
Y0111965*
X0672218*
Y0112019*
Y0112073*
X0672163*
Y0112127*
X0672109*
Y0112181*
X0672055*
Y0112235*
Y0112289*
X0672001*
Y0112343*
Y0112397*
X0671947*
Y0112452*
X0671893*
Y0112505*
Y011256*
X0671839*
Y0112614*
Y0112668*
X0671785*
Y0112722*
Y0112776*
X0671731*
Y011283*
Y0112884*
Y0112938*
X0671677*
Y0112992*
Y0113046*
Y01131*
X0671623*
Y0113154*
Y0113208*
Y0113262*
X0671569*
Y0113317*
Y0113371*
Y0113425*
Y0113479*
Y0113533*
X0671515*
Y0113587*
Y0113641*
Y0113695*
Y0113749*
Y0113803*
X0671461*
Y0113857*
Y0113911*
Y0113965*
Y0114019*
Y0114073*
Y0114127*
Y0114181*
Y0114235*
Y011429*
Y0114344*
Y0114398*
Y0114452*
Y0114506*
X0671515*
Y011456*
Y0114614*
Y0114668*
Y0114722*
Y0114776*
Y011483*
Y0114884*
X0671569*
Y0114938*
Y0114992*
Y0115047*
Y0115101*
X0671623*
Y0115155*
Y0115209*
Y0115263*
Y0115317*
X0671677*
Y0115371*
Y0115425*
X0671731*
Y0115479*
Y0115533*
Y0115587*
X0671785*
Y0115641*
Y0115695*
X0671839*
Y0115749*
Y0115803*
X0671893*
Y0115857*
Y0115911*
X0671947*
Y0115965*
Y011602*
X0672001*
Y0116074*
X0672055*
Y0116128*
Y0116182*
X0672109*
Y0116236*
X0672163*
Y011629*
Y0116344*
X0672218*
Y0116398*
X0672272*
Y0116452*
X0672326*
Y0116506*
X067238*
Y011656*
X0672434*
Y0116614*
X0672488*
Y0116668*
X0672542*
Y0116722*
X0672596*
Y0116776*
X067265*
Y0116831*
X0672704*
Y0116885*
X0672758*
Y0116939*
X0672812*
Y0116993*
X0672866*
Y0117047*
X0672974*
Y0117101*
X0673028*
Y0117155*
X0673137*
Y0117209*
X0673191*
Y0117263*
X0673299*
Y0117317*
X0673407*
Y0117371*
X0673515*
Y0117425*
X0673677*
Y0117479*
X0673785*
Y0117533*
X0673947*
Y0117587*
X0674164*
Y0117641*
X067438*
Y0117695*
X0674975*
Y011775*
X0679083*
Y0117695*
X0679137*
Y011775*
X0679191*
Y0117695*
G37*
G36*
X0597288Y0095098D02*
X0597504D01*
Y0095043*
X0597666*
Y009499*
X0597774*
Y0094935*
X0597882*
Y0094881*
X0597936*
Y0094827*
X0598044*
Y0094773*
X0598099*
Y0094719*
X0598207*
Y0094665*
X0598261*
Y0094611*
X0598315*
Y0094557*
X0598369*
Y0094503*
X0598423*
Y0094449*
X0598477*
Y0094395*
Y0094341*
X0598531*
Y0094287*
X0598585*
Y0094233*
Y0094178*
X0598639*
Y0094125*
X0598693*
Y009407*
Y0094016*
X0598747*
Y0093962*
Y0093908*
Y0093854*
X0598801*
Y00938*
Y0093746*
Y0093692*
X0598855*
Y0093638*
Y0093584*
Y009353*
Y0093476*
X0598909*
Y0093422*
Y0093368*
Y0093313*
Y009326*
Y0093205*
Y0093151*
Y0093097*
Y0093043*
Y0092989*
Y0092935*
Y0092881*
Y0092827*
Y0092773*
X0598855*
Y0092719*
Y0092665*
Y0092611*
Y0092557*
X0598801*
Y0092503*
Y0092449*
Y0092395*
X0598747*
Y009234*
Y0092286*
X0598693*
Y0092232*
Y0092178*
X0598639*
Y0092124*
Y009207*
X0598585*
Y0092016*
X0598531*
Y0091962*
Y0091908*
X0598477*
Y0091854*
X0598423*
Y00918*
X0598369*
Y0091746*
X0598315*
Y0091692*
X0598261*
Y0091638*
X0598207*
Y0091584*
X0598152*
Y009153*
X0598099*
Y0091475*
X059799*
Y0091421*
X0597936*
Y0091367*
X0597828*
Y0091313*
X059772*
Y0091259*
X0597558*
Y0091205*
X0597396*
Y0091151*
X0597071*
Y0091097*
X0596693*
Y0091151*
X0596369*
Y0091205*
X0596206*
Y0091259*
X0596098*
Y0091313*
X0595936*
Y0091367*
X0595882*
Y0091421*
X0595774*
Y0091475*
X059572*
Y009153*
X0595612*
Y0091584*
X0595558*
Y0091638*
X0595504*
Y0091692*
X0595449*
Y0091746*
X0595395*
Y00918*
X0595341*
Y0091854*
X0595287*
Y0091908*
X0595233*
Y0091962*
Y0092016*
X0595179*
Y009207*
Y0092124*
X0595125*
Y0092178*
X0595071*
Y0092232*
Y0092286*
X0595017*
Y009234*
Y0092395*
Y0092449*
X0594963*
Y0092503*
Y0092557*
Y0092611*
X0594909*
Y0092665*
Y0092719*
Y0092773*
Y0092827*
Y0092881*
X0594855*
Y0092935*
Y0092989*
Y0093043*
Y0093097*
Y0093151*
Y0093205*
Y009326*
Y0093313*
Y0093368*
Y0093422*
X0594909*
Y0093476*
Y009353*
Y0093584*
Y0093638*
Y0093692*
X0594963*
Y0093746*
Y00938*
Y0093854*
X0595017*
Y0093908*
Y0093962*
X0595071*
Y0094016*
Y009407*
X0595125*
Y0094125*
Y0094178*
X0595179*
Y0094233*
Y0094287*
X0595233*
Y0094341*
X0595287*
Y0094395*
X0595341*
Y0094449*
Y0094503*
X0595395*
Y0094557*
X0595449*
Y0094611*
X0595504*
Y0094665*
X0595612*
Y0094719*
X0595666*
Y0094773*
X059572*
Y0094827*
X0595828*
Y0094881*
X0595882*
Y0094935*
X059599*
Y009499*
X0596152*
Y0095043*
X059626*
Y0095098*
X0596477*
Y0095152*
X0597288*
Y0095098*
G37*
G36*
X0597233Y0087799D02*
X059745D01*
Y0087745*
X0597612*
Y0087691*
X059772*
Y0087637*
X0597828*
Y0087583*
X0597936*
Y0087529*
X0598044*
Y0087475*
X0598099*
Y0087421*
X0598152*
Y0087367*
X0598261*
Y0087313*
X0598315*
Y0087259*
X0598369*
Y0087204*
X0598423*
Y0087151*
Y0087096*
X0598477*
Y0087042*
X0598531*
Y0086988*
X0598585*
Y0086934*
Y008688*
X0598639*
Y0086826*
Y0086772*
X0598693*
Y0086718*
Y0086664*
X0598747*
Y008661*
Y0086556*
X0598801*
Y0086502*
Y0086448*
Y0086394*
X0598855*
Y0086339*
Y0086286*
Y0086231*
Y0086177*
X0598909*
Y0086123*
Y0086069*
Y0086015*
Y0085961*
Y0085907*
Y0085853*
Y0085799*
Y0085745*
Y0085691*
Y0085637*
Y0085583*
Y0085529*
Y0085474*
X0598855*
Y0085421*
Y0085366*
Y0085312*
Y0085258*
X0598801*
Y0085204*
Y008515*
Y0085096*
X0598747*
Y0085042*
Y0084988*
X0598693*
Y0084934*
Y008488*
X0598639*
Y0084826*
Y0084772*
X0598585*
Y0084718*
Y0084664*
X0598531*
Y008461*
X0598477*
Y0084556*
X0598423*
Y0084501*
Y0084447*
X0598369*
Y0084393*
X0598315*
Y0084339*
X0598207*
Y0084285*
X0598152*
Y0084231*
X0598099*
Y0084177*
X0598044*
Y0084123*
X0597936*
Y0084069*
X0597828*
Y0084015*
X059772*
Y0083961*
X0597612*
Y0083907*
X059745*
Y0083853*
X0597179*
Y0083799*
X0596585*
Y0083853*
X0596314*
Y0083907*
X0596152*
Y0083961*
X0596044*
Y0084015*
X0595936*
Y0084069*
X0595828*
Y0084123*
X0595774*
Y0084177*
X0595666*
Y0084231*
X0595612*
Y0084285*
X0595558*
Y0084339*
X0595504*
Y0084393*
X0595449*
Y0084447*
X0595395*
Y0084501*
X0595341*
Y0084556*
X0595287*
Y008461*
X0595233*
Y0084664*
Y0084718*
X0595179*
Y0084772*
X0595125*
Y0084826*
Y008488*
X0595071*
Y0084934*
Y0084988*
X0595017*
Y0085042*
Y0085096*
Y008515*
X0594963*
Y0085204*
Y0085258*
Y0085312*
X0594909*
Y0085366*
Y0085421*
Y0085474*
Y0085529*
X0594855*
Y0085583*
Y0085637*
Y0085691*
Y0085745*
Y0085799*
Y0085853*
Y0085907*
Y0085961*
Y0086015*
Y0086069*
Y0086123*
X0594909*
Y0086177*
Y0086231*
Y0086286*
Y0086339*
X0594963*
Y0086394*
Y0086448*
Y0086502*
Y0086556*
X0595017*
Y008661*
Y0086664*
X0595071*
Y0086718*
Y0086772*
X0595125*
Y0086826*
Y008688*
X0595179*
Y0086934*
X0595233*
Y0086988*
Y0087042*
X0595287*
Y0087096*
X0595341*
Y0087151*
X0595395*
Y0087204*
X0595449*
Y0087259*
X0595504*
Y0087313*
X0595558*
Y0087367*
X0595612*
Y0087421*
X0595666*
Y0087475*
X0595774*
Y0087529*
X0595828*
Y0087583*
X0595936*
Y0087637*
X0596044*
Y0087691*
X0596152*
Y0087745*
X0596314*
Y0087799*
X0596585*
Y0087853*
X0597233*
Y0087799*
G37*
G36*
X0691626Y0089475D02*
X069195D01*
Y0089421*
X0692166*
Y0089367*
X0692329*
Y0089313*
X0692491*
Y0089259*
X0692599*
Y0089205*
X0692761*
Y0089151*
X0692869*
Y0089097*
X0692923*
Y0089043*
X0693031*
Y0088989*
X069314*
Y0088934*
X0693194*
Y008888*
X0693302*
Y0088826*
X0693356*
Y0088772*
X069341*
Y0088718*
X0693464*
Y0088664*
X0693572*
Y008861*
X0693626*
Y0088556*
X069368*
Y0088502*
X0693734*
Y0088448*
X0693788*
Y0088394*
X0693842*
Y008834*
X0693896*
Y0088286*
X069395*
Y0088232*
Y0088178*
X0694004*
Y0088124*
X0694059*
Y0088069*
X0694113*
Y0088016*
Y0087961*
X0694167*
Y0087907*
X0694221*
Y0087853*
Y0087799*
X0694275*
Y0087745*
Y0087691*
X0694329*
Y0087637*
X0694383*
Y0087583*
Y0087529*
X0694437*
Y0087475*
Y0087421*
Y0087367*
X0694491*
Y0087313*
Y0087259*
X0694545*
Y0087204*
Y0087151*
Y0087096*
X0694599*
Y0087042*
Y0086988*
Y0086934*
X0694653*
Y008688*
Y0086826*
Y0086772*
Y0086718*
X0694707*
Y0086664*
Y008661*
Y0086556*
Y0086502*
Y0086448*
Y0086394*
X0694761*
Y0086339*
Y0086286*
Y0086231*
Y0086177*
Y0086123*
Y0086069*
Y0086015*
Y0085961*
Y0085907*
Y0085853*
Y0085799*
Y0085745*
Y0085691*
Y0085637*
Y0085583*
X0694707*
Y0085529*
Y0085474*
Y0085421*
Y0085366*
Y0085312*
Y0085258*
X0694653*
Y0085204*
Y008515*
Y0085096*
Y0085042*
X0694599*
Y0084988*
Y0084934*
Y008488*
X0694545*
Y0084826*
Y0084772*
Y0084718*
X0694491*
Y0084664*
Y008461*
X0694437*
Y0084556*
Y0084501*
X0694383*
Y0084447*
Y0084393*
X0694329*
Y0084339*
Y0084285*
X0694275*
Y0084231*
Y0084177*
X0694221*
Y0084123*
X0694167*
Y0084069*
Y0084015*
X0694113*
Y0083961*
X0694059*
Y0083907*
Y0083853*
X0694004*
Y0083799*
X069395*
Y0083745*
X0693896*
Y0083691*
X0693842*
Y0083636*
X0693788*
Y0083582*
X0693734*
Y0083528*
X069368*
Y0083474*
X0693626*
Y008342*
X0693572*
Y0083366*
X0693518*
Y0083312*
X0693464*
Y0083258*
X069341*
Y0083204*
X0693302*
Y008315*
X0693248*
Y0083096*
X0693194*
Y0083042*
X0693085*
Y0082988*
X0692977*
Y0082934*
X0692923*
Y008288*
X0692815*
Y0082825*
X0692707*
Y0082771*
X0692545*
Y0082717*
X0692437*
Y0082663*
X0692275*
Y0082609*
X0692058*
Y0082555*
X0691788*
Y0082501*
X0691464*
Y0082447*
X0691409*
Y0082501*
X0691356*
Y0082447*
X0691301*
Y0082501*
X0691247*
Y0082447*
X0690869*
Y0082501*
X069049*
Y0082555*
X069022*
Y0082609*
X0690058*
Y0082663*
X0689896*
Y0082717*
X0689734*
Y0082771*
X0689626*
Y0082825*
X0689517*
Y008288*
X0689409*
Y0082934*
X0689301*
Y0082988*
X0689247*
Y0083042*
X0689139*
Y0083096*
X0689085*
Y008315*
X0688977*
Y0083204*
X0688923*
Y0083258*
X0688869*
Y0083312*
X0688814*
Y0083366*
X0688706*
Y008342*
X0688652*
Y0083474*
X0688598*
Y0083528*
X0688544*
Y0083582*
X068849*
Y0083636*
X0688436*
Y0083691*
Y0083745*
X0688382*
Y0083799*
X0688328*
Y0083853*
X0688274*
Y0083907*
X068822*
Y0083961*
Y0084015*
X0688166*
Y0084069*
X0688112*
Y0084123*
Y0084177*
X0688058*
Y0084231*
Y0084285*
X0688004*
Y0084339*
X068795*
Y0084393*
Y0084447*
X0687895*
Y0084501*
Y0084556*
X0687841*
Y008461*
Y0084664*
Y0084718*
X0687787*
Y0084772*
Y0084826*
X0687733*
Y008488*
Y0084934*
Y0084988*
X0687679*
Y0085042*
Y0085096*
Y008515*
Y0085204*
X0687625*
Y0085258*
Y0085312*
Y0085366*
Y0085421*
Y0085474*
X0687571*
Y0085529*
Y0085583*
Y0085637*
Y0085691*
Y0085745*
Y0085799*
Y0085853*
Y0085907*
Y0085961*
Y0086015*
Y0086069*
Y0086123*
Y0086177*
Y0086231*
Y0086286*
Y0086339*
Y0086394*
Y0086448*
Y0086502*
X0687625*
Y0086556*
Y008661*
Y0086664*
Y0086718*
Y0086772*
X0687679*
Y0086826*
Y008688*
Y0086934*
Y0086988*
X0687733*
Y0087042*
Y0087096*
Y0087151*
X0687787*
Y0087204*
Y0087259*
Y0087313*
X0687841*
Y0087367*
Y0087421*
X0687895*
Y0087475*
Y0087529*
X068795*
Y0087583*
Y0087637*
X0688004*
Y0087691*
Y0087745*
X0688058*
Y0087799*
Y0087853*
X0688112*
Y0087907*
X0688166*
Y0087961*
Y0088016*
X068822*
Y0088069*
X0688274*
Y0088124*
X0688328*
Y0088178*
Y0088232*
X0688382*
Y0088286*
X0688436*
Y008834*
X068849*
Y0088394*
X0688544*
Y0088448*
X0688598*
Y0088502*
X0688652*
Y0088556*
X0688706*
Y008861*
X0688761*
Y0088664*
X0688814*
Y0088718*
X0688869*
Y0088772*
X0688977*
Y0088826*
X0689031*
Y008888*
X0689139*
Y0088934*
X0689193*
Y0088989*
X0689301*
Y0089043*
X0689355*
Y0089097*
X0689463*
Y0089151*
X0689571*
Y0089205*
X0689679*
Y0089259*
X0689842*
Y0089313*
X0690004*
Y0089367*
X0690166*
Y0089421*
X0690382*
Y0089475*
X0690653*
Y0089529*
X0691626*
Y0089475*
G37*
G36*
X0662919Y0117695D02*
X0663514D01*
Y0117641*
X066373*
Y0117587*
X0663946*
Y0117533*
X0664108*
Y0117479*
X066427*
Y0117425*
X0664378*
Y0117371*
X0664487*
Y0117317*
X0664595*
Y0117263*
X0664703*
Y0117209*
X0664811*
Y0117155*
X0664865*
Y0117101*
X0664973*
Y0117047*
X0665027*
Y0116993*
X0665081*
Y0116939*
X0665189*
Y0116885*
X0665243*
Y0116831*
X0665298*
Y0116776*
X0665352*
Y0116722*
X0665406*
Y0116668*
X066546*
Y0116614*
X0665514*
Y011656*
X0665568*
Y0116506*
X0665622*
Y0116452*
X0665676*
Y0116398*
X066573*
Y0116344*
Y011629*
X0665784*
Y0116236*
X0665838*
Y0116182*
X0665892*
Y0116128*
Y0116074*
X0665946*
Y011602*
Y0115965*
X0666*
Y0115911*
X0666054*
Y0115857*
Y0115803*
X0666109*
Y0115749*
Y0115695*
X0666163*
Y0115641*
Y0115587*
X0666217*
Y0115533*
Y0115479*
Y0115425*
X0666271*
Y0115371*
Y0115317*
Y0115263*
X0666325*
Y0115209*
Y0115155*
Y0115101*
X0666379*
Y0115047*
Y0114992*
Y0114938*
Y0114884*
X0666433*
Y011483*
Y0114776*
Y0114722*
Y0114668*
Y0114614*
Y011456*
X0666487*
Y0114506*
Y0114452*
Y0114398*
Y0114344*
Y011429*
Y0114235*
Y0114181*
Y0114127*
Y0114073*
Y0114019*
Y0113965*
X0666433*
Y0113911*
X0666487*
Y0113857*
X0666433*
Y0113803*
Y0113749*
Y0113695*
Y0113641*
Y0113587*
Y0113533*
Y0113479*
X0666379*
Y0113425*
Y0113371*
Y0113317*
Y0113262*
X0666325*
Y0113208*
Y0113154*
Y01131*
X0666271*
Y0113046*
Y0112992*
Y0112938*
X0666217*
Y0112884*
Y011283*
Y0112776*
X0666163*
Y0112722*
Y0112668*
X0666109*
Y0112614*
Y011256*
X0666054*
Y0112505*
Y0112452*
X0666*
Y0112397*
X0665946*
Y0112343*
Y0112289*
X0665892*
Y0112235*
X0665838*
Y0112181*
Y0112127*
X0665784*
Y0112073*
X066573*
Y0112019*
X0665676*
Y0111965*
Y0111911*
X0665622*
Y0111857*
X0665568*
Y0111803*
X0665514*
Y0111749*
X066546*
Y0111695*
X0665406*
Y0111641*
X0665352*
Y0111586*
X0665298*
Y0111532*
X0665243*
Y0111478*
X0665135*
Y0111424*
X0665081*
Y011137*
X0665027*
Y0111316*
X0664919*
Y0111262*
X0664865*
Y0111208*
X0664757*
Y0111154*
X0664703*
Y01111*
X0664595*
Y0111046*
X0664487*
Y0110992*
X0664378*
Y0110938*
X0664216*
Y0110884*
X0664108*
Y011083*
X0663892*
Y0110776*
X066373*
Y0110722*
X0663405*
Y0110668*
X0655242*
Y0110613*
X065481*
Y0110559*
X0654593*
Y0110505*
X0654377*
Y0110451*
X0654269*
Y0110397*
X0654107*
Y0110343*
X0653999*
Y0110289*
X0653891*
Y0110235*
X0653782*
Y0110181*
X0653674*
Y0110127*
X065362*
Y0110073*
X0653512*
Y0110019*
X0653404*
Y0109965*
X065335*
Y0109911*
X0653296*
Y0109856*
X0653242*
Y0109802*
X0653134*
Y0109748*
X065308*
Y0109694*
X0653025*
Y010964*
X0652971*
Y0109586*
X0652917*
Y0109532*
X0652863*
Y0109478*
X0652809*
Y0109424*
X0652755*
Y010937*
Y0109316*
X0652701*
Y0109262*
X0652647*
Y0109208*
X0652593*
Y0109154*
Y01091*
X0652539*
Y0109046*
X0652485*
Y0108992*
Y0108938*
X0652431*
Y0108883*
X0652377*
Y0108829*
Y0108775*
X0652323*
Y0108721*
Y0108667*
X0652269*
Y0108613*
Y0108559*
X0652214*
Y0108505*
Y0108451*
Y0108397*
X0652161*
Y0108343*
Y0108289*
X0652106*
Y0108235*
Y0108181*
Y0108126*
X0652052*
Y0108072*
Y0108018*
Y0107964*
Y010791*
X0651998*
Y0107856*
Y0107802*
Y0107748*
Y0107694*
Y010764*
Y0107586*
X0651944*
Y0107532*
Y0107478*
Y0107424*
Y010737*
Y0107316*
Y0107262*
Y0107208*
Y0107153*
Y0107099*
Y0107045*
Y0106991*
Y0106937*
Y0106883*
Y0106829*
Y0106775*
Y0106721*
X0651998*
Y0106667*
Y0106613*
Y0106559*
Y0106505*
Y0106451*
Y0106397*
X0652052*
Y0106342*
Y0106288*
Y0106234*
Y010618*
X0652106*
Y0106126*
Y0106072*
Y0106018*
X0652161*
Y0105964*
Y010591*
Y0105856*
X0652214*
Y0105802*
Y0105748*
X0652269*
Y0105694*
Y010564*
X0652323*
Y0105586*
Y0105532*
X0652377*
Y0105477*
Y0105423*
X0652431*
Y0105369*
Y0105315*
X0652485*
Y0105261*
X0652539*
Y0105207*
Y0105153*
X0652593*
Y0105099*
X0652647*
Y0105045*
Y0104991*
X0652701*
Y0104937*
X0652755*
Y0104883*
X0652809*
Y0104829*
X0652863*
Y0104775*
X0652917*
Y0104721*
X0652971*
Y0104667*
X0653025*
Y0104613*
X065308*
Y0104558*
X0653134*
Y0104504*
X0653188*
Y010445*
X0653242*
Y0104396*
X0653296*
Y0104342*
X0653404*
Y0104288*
X0653458*
Y0104234*
X0653566*
Y010418*
X065362*
Y0104126*
X0653728*
Y0104072*
X0653836*
Y0104018*
X0653944*
Y0103964*
X0654053*
Y010391*
X0654161*
Y0103856*
X0654323*
Y0103802*
X0654485*
Y0103747*
X0654701*
Y0103693*
X0654972*
Y0103639*
X0697735*
Y0103585*
X0697789*
Y0103639*
X0697843*
Y0103585*
X0698221*
Y0103531*
X0698438*
Y0103477*
X06986*
Y0103423*
X0698762*
Y0103369*
X0698924*
Y0103315*
X0699032*
Y0103261*
X069914*
Y0103207*
X0699249*
Y0103153*
X0699357*
Y0103099*
X0699411*
Y0103045*
X0699519*
Y0102991*
X0699573*
Y0102937*
X0699681*
Y0102883*
X0699735*
Y0102828*
X0699789*
Y0102774*
X0699843*
Y010272*
X0699951*
Y0102666*
X0700005*
Y0102612*
X0700059*
Y0102558*
X0700113*
Y0102504*
X0700168*
Y010245*
X0700222*
Y0102396*
Y0102342*
X0700276*
Y0102288*
X070033*
Y0102234*
X0700384*
Y010218*
X0700438*
Y0102126*
Y0102072*
X0700492*
Y0102017*
X0700546*
Y0101963*
Y0101909*
X07006*
Y0101855*
X0700654*
Y0101801*
Y0101747*
X0700708*
Y0101693*
Y0101639*
X0700762*
Y0101585*
Y0101531*
X0700816*
Y0101477*
Y0101423*
Y0101369*
X070087*
Y0101315*
Y0101261*
X0700924*
Y0101207*
Y0101153*
Y0101099*
X0700979*
Y0101044*
Y010099*
Y0100936*
Y0100882*
X0701032*
Y0100828*
Y0100774*
Y010072*
Y0100666*
Y0100612*
X0701087*
Y0100558*
Y0100504*
Y010045*
Y0100396*
Y0100342*
Y0100287*
Y0100233*
Y0100179*
Y0100125*
Y0100071*
Y0100017*
Y0099963*
Y0099909*
Y0099855*
Y0099801*
Y0099747*
Y0099693*
Y0099639*
Y0099585*
X0701032*
Y0099531*
Y0099477*
Y0099423*
Y0099369*
Y0099314*
X0700979*
Y009926*
Y0099206*
Y0099152*
Y0099098*
X0700924*
Y0099044*
Y009899*
Y0098936*
X070087*
Y0098882*
Y0098828*
Y0098774*
X0700816*
Y009872*
Y0098666*
X0700762*
Y0098612*
Y0098558*
X0700708*
Y0098504*
Y0098449*
X0700654*
Y0098395*
Y0098341*
X07006*
Y0098287*
Y0098233*
X0700546*
Y0098179*
X0700492*
Y0098125*
Y0098071*
X0700438*
Y0098017*
X0700384*
Y0097963*
X070033*
Y0097909*
X0700276*
Y0097855*
Y0097801*
X0700222*
Y0097747*
X0700168*
Y0097693*
X0700113*
Y0097638*
X0700059*
Y0097584*
X0700005*
Y009753*
X0699951*
Y0097476*
X0699897*
Y0097422*
X0699843*
Y0097368*
X0699735*
Y0097314*
X0699681*
Y009726*
X0699627*
Y0097206*
X0699519*
Y0097152*
X0699465*
Y0097098*
X0699357*
Y0097044*
X0699249*
Y009699*
X0699194*
Y0096936*
X0699032*
Y0096882*
X0698924*
Y0096828*
X0698816*
Y0096773*
X0698654*
Y0096719*
X0698492*
Y0096665*
X0698275*
Y0096611*
X0697951*
Y0096557*
X0669893*
Y0096503*
X0669568*
Y0096449*
X0669352*
Y0096395*
X0669136*
Y0096341*
X0669028*
Y0096287*
X0668866*
Y0096233*
X0668757*
Y0096179*
X0668649*
Y0096125*
X0668541*
Y0096071*
X0668433*
Y0096017*
X0668379*
Y0095963*
X0668271*
Y0095908*
X0668217*
Y0095854*
X0668163*
Y00958*
X0668055*
Y0095746*
X0668001*
Y0095692*
X0667947*
Y0095638*
X0667893*
Y0095584*
X0667838*
Y009553*
X0667784*
Y0095476*
X066773*
Y0095422*
X0667676*
Y0095368*
X0667622*
Y0095314*
X0667568*
Y009526*
X0667514*
Y0095206*
X066746*
Y0095152*
Y0095098*
X0667406*
Y0095043*
X0667352*
Y009499*
Y0094935*
X0667298*
Y0094881*
X0667244*
Y0094827*
Y0094773*
X066719*
Y0094719*
Y0094665*
X0667136*
Y0094611*
Y0094557*
X0667082*
Y0094503*
Y0094449*
X0667028*
Y0094395*
Y0094341*
X0666973*
Y0094287*
Y0094233*
Y0094178*
X0666919*
Y0094125*
Y009407*
Y0094016*
X0666865*
Y0093962*
Y0093908*
Y0093854*
Y00938*
X0666811*
Y0093746*
Y0093692*
Y0093638*
Y0093584*
Y009353*
Y0093476*
X0666757*
Y0093422*
Y0093368*
Y0093313*
Y009326*
Y0093205*
Y0093151*
Y0093097*
Y0093043*
Y0092989*
Y0092935*
Y0092881*
Y0092827*
Y0092773*
Y0092719*
Y0092665*
Y0092611*
X0666811*
Y0092557*
Y0092503*
Y0092449*
Y0092395*
Y009234*
Y0092286*
X0666865*
Y0092232*
Y0092178*
Y0092124*
Y009207*
X0666919*
Y0092016*
Y0091962*
Y0091908*
X0666973*
Y0091854*
Y00918*
Y0091746*
X0667028*
Y0091692*
Y0091638*
X0667082*
Y0091584*
Y009153*
X0667136*
Y0091475*
Y0091421*
X066719*
Y0091367*
Y0091313*
X0667244*
Y0091259*
Y0091205*
X0667298*
Y0091151*
X0667352*
Y0091097*
Y0091043*
X0667406*
Y0090989*
X066746*
Y0090935*
X0667514*
Y0090881*
Y0090827*
X0667568*
Y0090773*
X0667622*
Y0090719*
X0667676*
Y0090664*
X066773*
Y009061*
X0667784*
Y0090556*
X0667838*
Y0090502*
X0667893*
Y0090448*
X0667947*
Y0090394*
X0668001*
Y009034*
X0668109*
Y0090286*
X0668163*
Y0090232*
X0668217*
Y0090178*
X0668325*
Y0090124*
X0668379*
Y009007*
X0668487*
Y0090016*
X0668595*
Y0089962*
X0668649*
Y0089908*
X0668757*
Y0089854*
X066892*
Y0089799*
X0669028*
Y0089745*
X066919*
Y0089691*
X0669352*
Y0089637*
X0669568*
Y0089583*
X0669947*
Y0089529*
X0680327*
Y0089475*
X0680597*
Y0089421*
X0680813*
Y0089367*
X0680975*
Y0089313*
X0681138*
Y0089259*
X06813*
Y0089205*
X0681408*
Y0089151*
X0681516*
Y0089097*
X0681624*
Y0089043*
X0681732*
Y0088989*
X0681786*
Y0088934*
X0681895*
Y008888*
X0681949*
Y0088826*
X0682003*
Y0088772*
X0682111*
Y0088718*
X0682165*
Y0088664*
X0682219*
Y008861*
X0682273*
Y0088556*
X0682327*
Y0088502*
X0682381*
Y0088448*
X0682435*
Y0088394*
X0682489*
Y008834*
X0682543*
Y0088286*
X0682597*
Y0088232*
X0682652*
Y0088178*
X0682705*
Y0088124*
Y0088069*
X068276*
Y0088016*
X0682814*
Y0087961*
X0682868*
Y0087907*
Y0087853*
X0682922*
Y0087799*
Y0087745*
X0682976*
Y0087691*
X068303*
Y0087637*
Y0087583*
X0683084*
Y0087529*
Y0087475*
X0683138*
Y0087421*
Y0087367*
Y0087313*
X0683192*
Y0087259*
Y0087204*
X0683246*
Y0087151*
Y0087096*
Y0087042*
X06833*
Y0086988*
Y0086934*
Y008688*
Y0086826*
X0683354*
Y0086772*
Y0086718*
Y0086664*
Y008661*
Y0086556*
X0683408*
Y0086502*
Y0086448*
Y0086394*
Y0086339*
Y0086286*
Y0086231*
Y0086177*
Y0086123*
Y0086069*
Y0086015*
Y0085961*
Y0085907*
Y0085853*
Y0085799*
Y0085745*
Y0085691*
Y0085637*
Y0085583*
Y0085529*
Y0085474*
Y0085421*
X0683354*
Y0085366*
Y0085312*
Y0085258*
Y0085204*
Y008515*
X06833*
Y0085096*
Y0085042*
Y0084988*
X0683246*
Y0084934*
Y008488*
Y0084826*
X0683192*
Y0084772*
Y0084718*
Y0084664*
X0683138*
Y008461*
Y0084556*
X0683084*
Y0084501*
Y0084447*
X068303*
Y0084393*
Y0084339*
X0682976*
Y0084285*
Y0084231*
X0682922*
Y0084177*
Y0084123*
X0682868*
Y0084069*
X0682814*
Y0084015*
Y0083961*
X068276*
Y0083907*
X0682705*
Y0083853*
X0682652*
Y0083799*
X0682597*
Y0083745*
Y0083691*
X0682543*
Y0083636*
X0682489*
Y0083582*
X0682435*
Y0083528*
X0682381*
Y0083474*
X0682327*
Y008342*
X0682273*
Y0083366*
X0682219*
Y0083312*
X0682111*
Y0083258*
X0682057*
Y0083204*
X0682003*
Y008315*
X0681895*
Y0083096*
X0681841*
Y0083042*
X0681732*
Y0082988*
X0681678*
Y0082934*
X068157*
Y008288*
X0681462*
Y0082825*
X0681354*
Y0082771*
X0681246*
Y0082717*
X0681084*
Y0082663*
X0680922*
Y0082609*
X0680759*
Y0082555*
X0680489*
Y0082501*
X0680111*
Y0082447*
X0680002*
Y0082501*
X0679948*
Y0082447*
X066373*
Y0082501*
X0663676*
Y0082447*
X0663135*
Y0082393*
X0662865*
Y0082339*
X0662648*
Y0082285*
X0662486*
Y0082231*
X0662378*
Y0082177*
X0662216*
Y0082123*
X0662108*
Y0082069*
X0662*
Y0082015*
X0661946*
Y008196*
X0661838*
Y0081906*
X0661729*
Y0081852*
X0661675*
Y0081798*
X0661567*
Y0081744*
X0661513*
Y008169*
X0661459*
Y0081636*
X0661405*
Y0081582*
X0661297*
Y0081528*
X0661243*
Y0081474*
X0661189*
Y008142*
X0661135*
Y0081366*
X0661081*
Y0081312*
X0661027*
Y0081258*
Y0081204*
X0660973*
Y008115*
X0660919*
Y0081095*
X0660864*
Y0081042*
X066081*
Y0080987*
Y0080933*
X0660756*
Y0080879*
X0660702*
Y0080825*
Y0080771*
X0660648*
Y0080717*
X0660594*
Y0080663*
Y0080609*
X066054*
Y0080555*
Y0080501*
X0660486*
Y0080447*
Y0080393*
X0660432*
Y0080339*
Y0080285*
X0660378*
Y008023*
Y0080177*
Y0080122*
X0660324*
Y0080068*
Y0080014*
Y007996*
X066027*
Y0079906*
Y0079852*
Y0079798*
X0660216*
Y0079744*
Y007969*
Y0079636*
Y0079582*
Y0079528*
X0660162*
Y0079474*
Y007942*
Y0079365*
Y0079312*
Y0079257*
Y0079203*
Y0079149*
Y0079095*
Y0079041*
Y0078987*
Y0078933*
Y0078879*
Y0078825*
Y0078771*
Y0078717*
Y0078663*
Y0078609*
Y0078555*
Y00785*
Y0078447*
Y0078392*
X0660216*
Y0078338*
Y0078284*
Y007823*
Y0078176*
Y0078122*
X066027*
Y0078068*
Y0078014*
Y007796*
X0660324*
Y0077906*
Y0077852*
Y0077798*
X0660378*
Y0077744*
Y007769*
Y0077636*
X0660432*
Y0077582*
Y0077527*
X0660486*
Y0077473*
Y0077419*
X066054*
Y0077365*
Y0077311*
X0660594*
Y0077257*
Y0077203*
X0660648*
Y0077149*
Y0077095*
X0660702*
Y0077041*
X0660756*
Y0076987*
Y0076933*
X066081*
Y0076879*
X0660864*
Y0076825*
X0660919*
Y0076771*
Y0076717*
X0660973*
Y0076662*
X0661027*
Y0076608*
X0661081*
Y0076554*
X0661135*
Y00765*
X0661189*
Y0076446*
X0661243*
Y0076392*
X0661297*
Y0076338*
X0661351*
Y0076284*
X0661405*
Y007623*
X0661513*
Y0076176*
X0661567*
Y0076122*
X0661621*
Y0076068*
X0661729*
Y0076014*
X0661784*
Y007596*
X0661892*
Y0075906*
X0662*
Y0075852*
X0662108*
Y0075797*
X0662216*
Y0075743*
X0662324*
Y0075689*
X0662486*
Y0075635*
X0662595*
Y0075581*
X0662811*
Y0075527*
X0663081*
Y0075473*
X0663568*
Y0075419*
X0674758*
Y0075365*
X0675029*
Y0075311*
X0675191*
Y0075257*
X0675353*
Y0075203*
X0675515*
Y0075149*
X0675677*
Y0075095*
X0675786*
Y0075041*
X0675894*
Y0074986*
X0675948*
Y0074932*
X0676056*
Y0074878*
X0676164*
Y0074824*
X0676218*
Y007477*
X0676326*
Y0074716*
X067638*
Y0074662*
X0676434*
Y0074608*
X0676488*
Y0074554*
X0676596*
Y00745*
X0676651*
Y0074446*
X0676705*
Y0074392*
X0676759*
Y0074338*
X0676813*
Y0074284*
X0676867*
Y007423*
Y0074176*
X0676921*
Y0074121*
X0676975*
Y0074067*
X0677029*
Y0074013*
X0677083*
Y0073959*
Y0073905*
X0677137*
Y0073851*
X0677191*
Y0073797*
Y0073743*
X0677245*
Y0073689*
X0677299*
Y0073635*
Y0073581*
X0677353*
Y0073527*
Y0073473*
X0677407*
Y0073419*
Y0073365*
X0677461*
Y0073311*
Y0073256*
X0677516*
Y0073203*
Y0073148*
Y0073094*
X067757*
Y007304*
Y0072986*
Y0072932*
X0677624*
Y0072878*
Y0072824*
Y007277*
X0677678*
Y0072716*
Y0072662*
Y0072608*
Y0072554*
Y00725*
Y0072446*
X0677732*
Y0072391*
Y0072338*
Y0072283*
Y0072229*
Y0072175*
Y0072121*
Y0072067*
Y0072013*
Y0071959*
X0677786*
Y0071905*
Y0071851*
X0677732*
Y0071797*
Y0071743*
Y0071689*
Y0071635*
Y0071581*
Y0071526*
Y0071473*
Y0071418*
Y0071364*
Y007131*
X0677678*
Y0071256*
Y0071202*
Y0071148*
Y0071094*
Y007104*
X0677624*
Y0070986*
Y0070932*
Y0070878*
X067757*
Y0070824*
Y007077*
Y0070716*
X0677516*
Y0070662*
Y0070608*
Y0070553*
X0677461*
Y0070499*
Y0070445*
Y0070391*
X0677407*
Y0070337*
Y0070283*
X0677353*
Y0070229*
Y0070175*
X0677299*
Y0070121*
Y0070067*
X0677245*
Y0070013*
X0677191*
Y0069959*
Y0069905*
X0677137*
Y0069851*
X0677083*
Y0069797*
Y0069743*
X0677029*
Y0069688*
X0676975*
Y0069634*
X0676921*
Y006958*
Y0069526*
X0676867*
Y0069472*
X0676813*
Y0069418*
X0676759*
Y0069364*
X0676705*
Y006931*
X0676651*
Y0069256*
X0676596*
Y0069202*
X0676543*
Y0069148*
X0676488*
Y0069094*
X0676434*
Y006904*
X067638*
Y0068986*
X0676272*
Y0068932*
X0676218*
Y0068878*
X0676164*
Y0068823*
X0676056*
Y0068769*
X0676002*
Y0068715*
X0675894*
Y0068661*
X0675786*
Y0068607*
X0675677*
Y0068553*
X0675569*
Y0068499*
X0675407*
Y0068445*
X0675191*
Y0068391*
X0636266*
Y0068337*
X0636158*
Y0068283*
X0636104*
Y0068229*
X063605*
Y0068175*
X0635996*
Y0068121*
Y0068067*
X0635942*
Y0068012*
Y0067958*
Y0067904*
Y006785*
Y0067796*
Y0067742*
Y0067688*
Y0067634*
Y006758*
Y0067526*
Y0067472*
Y0067418*
Y0067364*
Y006731*
Y0067256*
Y0067202*
Y0067147*
Y0067093*
Y0067039*
Y0066985*
Y0066931*
Y0066877*
Y0066823*
Y0066769*
Y0066715*
Y0066661*
Y0066607*
Y0066553*
Y0066499*
Y0066445*
Y0066391*
Y0066337*
Y0066282*
Y0066228*
Y0066174*
Y006612*
Y0066066*
Y0066012*
Y0065958*
Y0065904*
Y006585*
Y0065796*
Y0065742*
Y0065688*
Y0065634*
Y006558*
Y0065526*
Y0065472*
Y0065417*
Y0065364*
Y0065309*
Y0065255*
Y0065201*
Y0065147*
Y0065093*
Y0065039*
Y0064985*
Y0064931*
Y0064877*
Y0064823*
Y0064769*
Y0064715*
Y0064661*
Y0064607*
Y0064552*
Y0064499*
Y0064444*
Y006439*
Y0064336*
Y0064282*
Y0064228*
Y0064174*
Y006412*
Y0064066*
Y0064012*
Y0063958*
Y0063904*
Y006385*
Y0063796*
Y0063742*
Y0063688*
Y0063634*
Y0063579*
Y0063525*
Y0063471*
Y0063417*
Y0063363*
Y0063309*
Y0063255*
Y0063201*
Y0063147*
Y0063093*
Y0063039*
Y0062985*
Y0062931*
Y0062877*
Y0062823*
Y0062769*
Y0062714*
X0635888*
Y006266*
Y0062606*
X0635834*
Y0062552*
Y0062498*
X063578*
Y0062444*
X0635672*
Y006239*
X0635564*
Y0062336*
X0625238*
Y006239*
X0625075*
Y0062444*
X0625021*
Y0062498*
X0624967*
Y0062552*
X0624913*
Y0062606*
Y006266*
X0624859*
Y0062714*
Y0062769*
Y0062823*
Y0062877*
Y0062931*
Y0062985*
Y0063039*
Y0063093*
Y0063147*
Y0063201*
Y0063255*
Y0063309*
Y0063363*
Y0063417*
Y0063471*
Y0063525*
Y0063579*
Y0063634*
Y0063688*
Y0063742*
Y0063796*
Y006385*
Y0063904*
Y0063958*
Y0064012*
Y0064066*
Y006412*
Y0064174*
Y0064228*
Y0064282*
Y0064336*
Y006439*
Y0064444*
Y0064499*
Y0064552*
Y0064607*
Y0064661*
Y0064715*
Y0064769*
Y0064823*
Y0064877*
Y0064931*
Y0064985*
Y0065039*
Y0065093*
Y0065147*
Y0065201*
Y0065255*
Y0065309*
Y0065364*
Y0065417*
Y0065472*
Y0065526*
Y006558*
Y0065634*
Y0065688*
Y0065742*
Y0065796*
Y006585*
Y0065904*
Y0065958*
X0624805*
Y0066012*
Y0066066*
Y006612*
X0624751*
Y0066174*
Y0066228*
X0624697*
Y0066282*
X0624589*
Y0066337*
X0624427*
Y0066391*
X0624264*
Y0066337*
X0624102*
Y0066282*
X0624048*
Y0066228*
X0623994*
Y0066174*
X062394*
Y006612*
X0623886*
Y0066066*
Y0066012*
Y0065958*
Y0065904*
X0623832*
Y006585*
Y0065796*
Y0065742*
Y0065688*
Y0065634*
Y006558*
Y0065526*
Y0065472*
Y0065417*
Y0065364*
Y0065309*
Y0065255*
Y0065201*
Y0065147*
Y0065093*
Y0065039*
Y0064985*
Y0064931*
Y0064877*
Y0064823*
Y0064769*
Y0064715*
Y0064661*
Y0064607*
Y0064552*
Y0064499*
Y0064444*
Y006439*
Y0064336*
Y0064282*
Y0064228*
Y0064174*
Y006412*
Y0064066*
Y0064012*
Y0063958*
Y0063904*
Y006385*
Y0063796*
Y0063742*
Y0063688*
Y0063634*
Y0063579*
Y0063525*
Y0063471*
Y0063417*
Y0063363*
Y0063309*
Y0063255*
Y0063201*
Y0063147*
Y0063093*
Y0063039*
Y0062985*
Y0062931*
Y0062877*
Y0062823*
Y0062769*
Y0062714*
Y006266*
Y0062606*
X0623778*
Y0062552*
X0623724*
Y0062498*
X062367*
Y0062444*
X0623616*
Y006239*
X0623454*
Y0062336*
X0618155*
Y006239*
X0618047*
Y0062444*
X0617939*
Y0062498*
X0617885*
Y0062552*
Y0062606*
X0617831*
Y006266*
Y0062714*
Y0062769*
X0617777*
Y0062823*
Y0062877*
Y0062931*
Y0062985*
Y0063039*
Y0063093*
Y0063147*
Y0063201*
Y0063255*
Y0063309*
Y0063363*
Y0063417*
Y0063471*
Y0063525*
Y0063579*
Y0063634*
Y0063688*
Y0063742*
Y0063796*
Y006385*
Y0063904*
Y0063958*
Y0064012*
Y0064066*
Y006412*
Y0064174*
Y0064228*
Y0064282*
Y0064336*
Y006439*
Y0064444*
Y0064499*
Y0064552*
Y0064607*
Y0064661*
Y0064715*
Y0064769*
Y0064823*
Y0064877*
Y0064931*
Y0064985*
Y0065039*
Y0065093*
Y0065147*
Y0065201*
Y0065255*
Y0065309*
Y0065364*
Y0065417*
Y0065472*
Y0065526*
Y006558*
Y0065634*
Y0065688*
Y0065742*
Y0065796*
Y006585*
Y0065904*
Y0065958*
Y0066012*
Y0066066*
Y006612*
Y0066174*
Y0066228*
Y0066282*
Y0066337*
Y0066391*
Y0066445*
Y0066499*
Y0066553*
Y0066607*
Y0066661*
Y0066715*
Y0066769*
Y0066823*
Y0066877*
Y0066931*
Y0066985*
Y0067039*
Y0067093*
Y0067147*
X0617831*
Y0067202*
X0617777*
Y0067256*
Y006731*
Y0067364*
Y0067418*
Y0067472*
Y0067526*
Y006758*
Y0067634*
Y0067688*
X0617723*
Y0067742*
Y0067796*
X0617669*
Y006785*
Y0067904*
X0617615*
Y0067958*
Y0068012*
X0617561*
Y0068067*
X0617507*
Y0068121*
X0617453*
Y0068175*
X0617399*
Y0068229*
X061729*
Y0068283*
X0617182*
Y0068337*
X061702*
Y0068391*
X0616588*
Y0068337*
X0616426*
Y0068283*
X0616317*
Y0068229*
X0616209*
Y0068175*
X0616155*
Y0068121*
X0616101*
Y0068067*
X0616047*
Y0068012*
X0615993*
Y0067958*
X0615939*
Y0067904*
Y006785*
X0615885*
Y0067796*
Y0067742*
X0615831*
Y0067688*
Y0067634*
Y006758*
Y0067526*
Y0067472*
Y0067418*
X0615777*
Y0067364*
X0615831*
Y006731*
Y0067256*
X0615777*
Y0067202*
X0615831*
Y0067147*
Y0067093*
Y0067039*
Y0066985*
Y0066931*
Y0066877*
Y0066823*
Y0066769*
Y0066715*
Y0066661*
Y0066607*
Y0066553*
Y0066499*
Y0066445*
Y0066391*
Y0066337*
Y0066282*
Y0066228*
Y0066174*
Y006612*
Y0066066*
Y0066012*
Y0065958*
Y0065904*
Y006585*
Y0065796*
Y0065742*
Y0065688*
Y0065634*
Y006558*
Y0065526*
Y0065472*
Y0065417*
Y0065364*
Y0065309*
Y0065255*
Y0065201*
Y0065147*
Y0065093*
Y0065039*
Y0064985*
Y0064931*
Y0064877*
X0615777*
Y0064823*
Y0064769*
Y0064715*
Y0064661*
X0615723*
Y0064607*
X0615669*
Y0064552*
X0615615*
Y0064499*
X061556*
Y0064444*
X0615398*
Y006439*
X0612155*
Y0064444*
X0611992*
Y0064499*
X0611938*
Y0064552*
X0611884*
Y0064607*
X061183*
Y0064661*
X0611776*
Y0064715*
Y0064769*
Y0064823*
X0611722*
Y0064877*
Y0064931*
Y0064985*
Y0065039*
Y0065093*
Y0065147*
Y0065201*
Y0065255*
Y0065309*
Y0065364*
Y0065417*
Y0065472*
Y0065526*
Y006558*
Y0065634*
Y0065688*
Y0065742*
Y0065796*
Y006585*
Y0065904*
Y0065958*
Y0066012*
Y0066066*
Y006612*
Y0066174*
Y0066228*
Y0066282*
Y0066337*
Y0066391*
Y0066445*
Y0066499*
Y0066553*
Y0066607*
Y0066661*
Y0066715*
Y0066769*
Y0066823*
Y0066877*
Y0066931*
Y0066985*
Y0067039*
Y0067093*
Y0067147*
Y0067202*
Y0067256*
Y006731*
Y0067364*
Y0067418*
Y0067472*
Y0067526*
Y006758*
X0611776*
Y0067634*
Y0067688*
X0611722*
Y0067742*
X0611776*
Y0067796*
X0611722*
Y006785*
Y0067904*
Y0067958*
Y0068012*
Y0068067*
Y0068121*
X0611668*
Y0068175*
Y0068229*
X0611614*
Y0068283*
X0611506*
Y0068337*
X0611398*
Y0068391*
X0603018*
Y0068337*
X060291*
Y0068283*
X0602856*
Y0068229*
X0602802*
Y0068175*
X0602748*
Y0068121*
Y0068067*
X0602694*
Y0068012*
Y0067958*
Y0067904*
Y006785*
Y0067796*
Y0067742*
Y0067688*
Y0067634*
Y006758*
Y0067526*
Y0067472*
Y0067418*
Y0067364*
Y006731*
Y0067256*
Y0067202*
Y0067147*
Y0067093*
Y0067039*
Y0066985*
Y0066931*
Y0066877*
Y0066823*
Y0066769*
Y0066715*
Y0066661*
Y0066607*
Y0066553*
Y0066499*
Y0066445*
Y0066391*
Y0066337*
Y0066282*
Y0066228*
Y0066174*
Y006612*
Y0066066*
Y0066012*
Y0065958*
Y0065904*
Y006585*
Y0065796*
Y0065742*
Y0065688*
Y0065634*
Y006558*
Y0065526*
Y0065472*
Y0065417*
Y0065364*
Y0065309*
Y0065255*
Y0065201*
Y0065147*
Y0065093*
Y0065039*
Y0064985*
Y0064931*
Y0064877*
Y0064823*
Y0064769*
Y0064715*
Y0064661*
Y0064607*
Y0064552*
Y0064499*
Y0064444*
Y006439*
Y0064336*
Y0064282*
Y0064228*
Y0064174*
Y006412*
Y0064066*
Y0064012*
Y0063958*
Y0063904*
Y006385*
Y0063796*
Y0063742*
Y0063688*
Y0063634*
Y0063579*
Y0063525*
Y0063471*
Y0063417*
Y0063363*
X0594638*
Y0063417*
Y0063471*
Y0063525*
Y0063579*
Y0063634*
Y0063688*
Y0063742*
Y0063796*
Y006385*
Y0063904*
Y0063958*
Y0064012*
Y0064066*
Y006412*
Y0064174*
Y0064228*
Y0064282*
Y0064336*
Y006439*
Y0064444*
Y0064499*
Y0064552*
Y0064607*
Y0064661*
Y0064715*
Y0064769*
Y0064823*
Y0064877*
Y0064931*
Y0064985*
Y0065039*
Y0065093*
Y0065147*
Y0065201*
Y0065255*
Y0065309*
Y0065364*
Y0065417*
Y0065472*
Y0065526*
Y006558*
Y0065634*
Y0065688*
Y0065742*
Y0065796*
Y006585*
Y0065904*
Y0065958*
Y0066012*
Y0066066*
Y006612*
Y0066174*
Y0066228*
Y0066282*
Y0066337*
Y0066391*
Y0066445*
Y0066499*
Y0066553*
Y0066607*
Y0066661*
Y0066715*
Y0066769*
Y0066823*
Y0066877*
Y0066931*
Y0066985*
Y0067039*
Y0067093*
Y0067147*
Y0067202*
Y0067256*
Y006731*
Y0067364*
Y0067418*
Y0067472*
Y0067526*
Y006758*
Y0067634*
Y0067688*
Y0067742*
Y0067796*
Y006785*
Y0067904*
Y0067958*
Y0068012*
Y0068067*
Y0068121*
Y0068175*
Y0068229*
X0599883*
Y0068283*
Y0068337*
Y0068391*
Y0068445*
Y0068499*
Y0068553*
Y0068607*
Y0068661*
Y0068715*
Y0068769*
Y0068823*
Y0068878*
Y0068932*
Y0068986*
Y006904*
Y0069094*
Y0069148*
Y0069202*
Y0069256*
Y006931*
Y0069364*
Y0069418*
Y0069472*
Y0069526*
Y006958*
Y0069634*
Y0069688*
Y0069743*
Y0069797*
Y0069851*
Y0069905*
Y0069959*
Y0070013*
Y0070067*
Y0070121*
Y0070175*
Y0070229*
Y0070283*
Y0070337*
Y0070391*
Y0070445*
Y0070499*
Y0070553*
Y0070608*
Y0070662*
Y0070716*
Y007077*
Y0070824*
Y0070878*
Y0070932*
Y0070986*
Y007104*
Y0071094*
Y0071148*
Y0071202*
Y0071256*
Y007131*
Y0071364*
Y0071418*
Y0071473*
Y0071526*
Y0071581*
Y0071635*
Y0071689*
Y0071743*
Y0071797*
Y0071851*
Y0071905*
Y0071959*
Y0072013*
Y0072067*
Y0072121*
Y0072175*
Y0072229*
Y0072283*
Y0072338*
Y0072391*
Y0072446*
Y00725*
Y0072554*
Y0072608*
Y0072662*
Y0072716*
Y007277*
Y0072824*
Y0072878*
Y0072932*
Y0072986*
Y007304*
Y0073094*
Y0073148*
Y0073203*
Y0073256*
Y0073311*
Y0073365*
Y0073419*
Y0073473*
Y0073527*
Y0073581*
Y0073635*
Y0073689*
Y0073743*
Y0073797*
Y0073851*
Y0073905*
Y0073959*
Y0074013*
Y0074067*
Y0074121*
Y0074176*
X0594638*
Y007423*
Y0074284*
Y0074338*
Y0074392*
Y0074446*
Y00745*
Y0074554*
Y0074608*
Y0074662*
Y0074716*
Y007477*
Y0074824*
Y0074878*
Y0074932*
Y0074986*
Y0075041*
Y0075095*
Y0075149*
Y0075203*
Y0075257*
Y0075311*
Y0075365*
Y0075419*
Y0075473*
Y0075527*
X0599883*
Y0075581*
Y0075635*
Y0075689*
Y0075743*
Y0075797*
Y0075852*
Y0075906*
Y007596*
Y0076014*
Y0076068*
Y0076122*
Y0076176*
Y007623*
Y0076284*
Y0076338*
Y0076392*
Y0076446*
Y00765*
Y0076554*
Y0076608*
Y0076662*
Y0076717*
Y0076771*
Y0076825*
Y0076879*
Y0076933*
Y0076987*
Y0077041*
Y0077095*
Y0077149*
Y0077203*
Y0077257*
Y0077311*
Y0077365*
Y0077419*
Y0077473*
Y0077527*
Y0077582*
Y0077636*
Y007769*
Y0077744*
Y0077798*
Y0077852*
Y0077906*
Y007796*
Y0078014*
Y0078068*
Y0078122*
Y0078176*
Y007823*
Y0078284*
Y0078338*
Y0078392*
Y0078447*
Y00785*
Y0078555*
Y0078609*
Y0078663*
Y0078717*
Y0078771*
Y0078825*
Y0078879*
Y0078933*
Y0078987*
Y0079041*
Y0079095*
Y0079149*
Y0079203*
Y0079257*
Y0079312*
Y0079365*
Y007942*
Y0079474*
Y0079528*
Y0079582*
Y0079636*
Y007969*
Y0079744*
Y0079798*
Y0079852*
Y0079906*
Y007996*
Y0080014*
Y0080068*
Y0080122*
Y0080177*
Y008023*
Y0080285*
Y0080339*
Y0080393*
Y0080447*
Y0080501*
Y0080555*
Y0080609*
Y0080663*
Y0080717*
Y0080771*
Y0080825*
Y0080879*
Y0080933*
Y0080987*
Y0081042*
Y0081095*
Y008115*
Y0081204*
Y0081258*
Y0081312*
Y0081366*
Y008142*
Y0081474*
X0594693*
Y0081528*
X0594638*
Y0081582*
Y0081636*
Y008169*
Y0081744*
Y0081798*
Y0081852*
Y0081906*
Y008196*
Y0082015*
Y0082069*
Y0082123*
Y0082177*
Y0082231*
Y0082285*
Y0082339*
Y0082393*
Y0082447*
Y0082501*
Y0082555*
Y0082609*
Y0082663*
Y0082717*
Y0082771*
Y0082825*
X0599883*
Y008288*
Y0082934*
Y0082988*
Y0083042*
Y0083096*
Y008315*
Y0083204*
Y0083258*
Y0083312*
Y0083366*
Y008342*
Y0083474*
Y0083528*
Y0083582*
Y0083636*
Y0083691*
Y0083745*
Y0083799*
Y0083853*
Y0083907*
Y0083961*
Y0084015*
Y0084069*
Y0084123*
Y0084177*
Y0084231*
Y0084285*
Y0084339*
Y0084393*
Y0084447*
Y0084501*
Y0084556*
Y008461*
Y0084664*
Y0084718*
Y0084772*
Y0084826*
Y008488*
Y0084934*
Y0084988*
Y0085042*
Y0085096*
Y008515*
Y0085204*
Y0085258*
Y0085312*
Y0085366*
Y0085421*
Y0085474*
Y0085529*
Y0085583*
Y0085637*
Y0085691*
Y0085745*
Y0085799*
Y0085853*
Y0085907*
Y0085961*
Y0086015*
Y0086069*
Y0086123*
Y0086177*
Y0086231*
Y0086286*
Y0086339*
Y0086394*
Y0086448*
Y0086502*
Y0086556*
Y008661*
Y0086664*
Y0086718*
Y0086772*
Y0086826*
Y008688*
Y0086934*
Y0086988*
Y0087042*
Y0087096*
Y0087151*
Y0087204*
Y0087259*
Y0087313*
Y0087367*
Y0087421*
Y0087475*
Y0087529*
Y0087583*
Y0087637*
Y0087691*
Y0087745*
Y0087799*
Y0087853*
Y0087907*
Y0087961*
Y0088016*
Y0088069*
Y0088124*
Y0088178*
Y0088232*
Y0088286*
Y008834*
Y0088394*
Y0088448*
Y0088502*
Y0088556*
Y008861*
Y0088664*
Y0088718*
Y0088772*
Y0088826*
X0594638*
Y008888*
Y0088934*
Y0088989*
Y0089043*
Y0089097*
Y0089151*
Y0089205*
Y0089259*
Y0089313*
Y0089367*
Y0089421*
Y0089475*
Y0089529*
Y0089583*
Y0089637*
Y0089691*
Y0089745*
Y0089799*
Y0089854*
Y0089908*
Y0089962*
Y0090016*
Y009007*
Y0090124*
X0594693*
Y0090178*
X0599883*
Y0090232*
Y0090286*
Y009034*
Y0090394*
Y0090448*
Y0090502*
Y0090556*
Y009061*
Y0090664*
Y0090719*
Y0090773*
Y0090827*
Y0090881*
Y0090935*
Y0090989*
Y0091043*
Y0091097*
Y0091151*
Y0091205*
Y0091259*
Y0091313*
Y0091367*
Y0091421*
Y0091475*
Y009153*
Y0091584*
Y0091638*
Y0091692*
Y0091746*
Y00918*
Y0091854*
Y0091908*
Y0091962*
Y0092016*
Y009207*
Y0092124*
Y0092178*
Y0092232*
Y0092286*
Y009234*
Y0092395*
Y0092449*
Y0092503*
Y0092557*
Y0092611*
Y0092665*
Y0092719*
Y0092773*
Y0092827*
Y0092881*
Y0092935*
Y0092989*
Y0093043*
Y0093097*
Y0093151*
Y0093205*
Y009326*
Y0093313*
Y0093368*
Y0093422*
Y0093476*
Y009353*
Y0093584*
Y0093638*
Y0093692*
Y0093746*
Y00938*
Y0093854*
Y0093908*
Y0093962*
Y0094016*
Y009407*
Y0094125*
Y0094178*
Y0094233*
Y0094287*
Y0094341*
Y0094395*
Y0094449*
Y0094503*
Y0094557*
Y0094611*
Y0094665*
Y0094719*
Y0094773*
Y0094827*
Y0094881*
Y0094935*
Y009499*
Y0095043*
Y0095098*
Y0095152*
Y0095206*
Y009526*
Y0095314*
Y0095368*
Y0095422*
Y0095476*
Y009553*
Y0095584*
Y0095638*
Y0095692*
Y0095746*
Y00958*
Y0095854*
Y0095908*
Y0095963*
Y0096017*
Y0096071*
Y0096125*
X0594638*
Y0096179*
Y0096233*
Y0096287*
Y0096341*
Y0096395*
Y0096449*
Y0096503*
Y0096557*
Y0096611*
Y0096665*
Y0096719*
Y0096773*
Y0096828*
Y0096882*
Y0096936*
Y009699*
Y0097044*
Y0097098*
Y0097152*
Y0097206*
Y009726*
Y0097314*
Y0097368*
Y0097422*
Y0097476*
Y009753*
Y0097584*
Y0097638*
Y0097693*
Y0097747*
Y0097801*
Y0097855*
Y0097909*
Y0097963*
Y0098017*
Y0098071*
Y0098125*
Y0098179*
Y0098233*
Y0098287*
Y0098341*
Y0098395*
Y0098449*
Y0098504*
Y0098558*
Y0098612*
Y0098666*
Y009872*
Y0098774*
Y0098828*
Y0098882*
Y0098936*
Y009899*
Y0099044*
Y0099098*
Y0099152*
Y0099206*
Y009926*
Y0099314*
Y0099369*
Y0099423*
Y0099477*
Y0099531*
Y0099585*
Y0099639*
Y0099693*
Y0099747*
Y0099801*
Y0099855*
Y0099909*
Y0099963*
Y0100017*
Y0100071*
Y0100125*
Y0100179*
Y0100233*
Y0100287*
Y0100342*
Y0100396*
Y010045*
Y0100504*
Y0100558*
Y0100612*
Y0100666*
Y010072*
Y0100774*
Y0100828*
Y0100882*
Y0100936*
Y010099*
Y0101044*
Y0101099*
Y0101153*
Y0101207*
Y0101261*
Y0101315*
Y0101369*
Y0101423*
Y0101477*
Y0101531*
Y0101585*
Y0101639*
Y0101693*
Y0101747*
Y0101801*
Y0101855*
Y0101909*
Y0101963*
Y0102017*
Y0102072*
Y0102126*
Y010218*
Y0102234*
Y0102288*
Y0102342*
Y0102396*
Y010245*
Y0102504*
Y0102558*
Y0102612*
Y0102666*
Y010272*
Y0102774*
Y0102828*
Y0102883*
Y0102937*
Y0102991*
Y0103045*
Y0103099*
Y0103153*
Y0103207*
Y0103261*
Y0103315*
Y0103369*
Y0103423*
Y0103477*
Y0103531*
Y0103585*
Y0103639*
Y0103693*
Y0103747*
Y0103802*
Y0103856*
Y010391*
Y0103964*
Y0104018*
Y0104072*
Y0104126*
Y010418*
Y0104234*
Y0104288*
Y0104342*
Y0104396*
Y010445*
Y0104504*
Y0104558*
Y0104613*
Y0104667*
Y0104721*
Y0104775*
Y0104829*
Y0104883*
Y0104937*
Y0104991*
Y0105045*
Y0105099*
Y0105153*
Y0105207*
Y0105261*
Y0105315*
Y0105369*
Y0105423*
Y0105477*
Y0105532*
Y0105586*
Y010564*
Y0105694*
Y0105748*
Y0105802*
Y0105856*
Y010591*
Y0105964*
Y0106018*
Y0106072*
Y0106126*
Y010618*
Y0106234*
Y0106288*
Y0106342*
Y0106397*
Y0106451*
Y0106505*
Y0106559*
Y0106613*
Y0106667*
Y0106721*
Y0106775*
Y0106829*
Y0106883*
Y0106937*
Y0106991*
Y0107045*
Y0107099*
Y0107153*
Y0107208*
Y0107262*
Y0107316*
Y010737*
Y0107424*
Y0107478*
Y0107532*
Y0107586*
Y010764*
Y0107694*
Y0107748*
Y0107802*
Y0107856*
Y010791*
Y0107964*
Y0108018*
Y0108072*
Y0108126*
Y0108181*
Y0108235*
Y0108289*
Y0108343*
Y0108397*
Y0108451*
Y0108505*
Y0108559*
Y0108613*
Y0108667*
Y0108721*
Y0108775*
Y0108829*
Y0108883*
Y0108938*
Y0108992*
Y0109046*
Y01091*
Y0109154*
Y0109208*
Y0109262*
Y0109316*
Y010937*
Y0109424*
Y0109478*
Y0109532*
Y0109586*
Y010964*
Y0109694*
Y0109748*
Y0109802*
Y0109856*
Y0109911*
Y0109965*
Y0110019*
Y0110073*
Y0110127*
Y0110181*
Y0110235*
Y0110289*
Y0110343*
Y0110397*
Y0110451*
Y0110505*
Y0110559*
Y0110613*
Y0110668*
Y0110722*
Y0110776*
Y011083*
Y0110884*
Y0110938*
Y0110992*
Y0111046*
Y01111*
Y0111154*
Y0111208*
Y0111262*
Y0111316*
Y011137*
Y0111424*
Y0111478*
Y0111532*
Y0111586*
Y0111641*
Y0111695*
Y0111749*
Y0111803*
Y0111857*
Y0111911*
Y0111965*
Y0112019*
Y0112073*
Y0112127*
Y0112181*
Y0112235*
Y0112289*
Y0112343*
Y0112397*
Y0112452*
Y0112505*
Y011256*
Y0112614*
Y0112668*
Y0112722*
Y0112776*
Y011283*
Y0112884*
Y0112938*
Y0112992*
Y0113046*
Y01131*
Y0113154*
Y0113208*
Y0113262*
Y0113317*
Y0113371*
Y0113425*
Y0113479*
Y0113533*
Y0113587*
Y0113641*
Y0113695*
Y0113749*
Y0113803*
Y0113857*
Y0113911*
Y0113965*
Y0114019*
Y0114073*
Y0114127*
Y0114181*
Y0114235*
Y011429*
Y0114344*
Y0114398*
Y0114452*
Y0114506*
Y011456*
Y0114614*
Y0114668*
Y0114722*
Y0114776*
Y011483*
Y0114884*
Y0114938*
Y0114992*
Y0115047*
Y0115101*
Y0115155*
Y0115209*
Y0115263*
Y0115317*
Y0115371*
Y0115425*
Y0115479*
Y0115533*
Y0115587*
Y0115641*
Y0115695*
Y0115749*
Y0115803*
Y0115857*
Y0115911*
Y0115965*
Y011602*
Y0116074*
Y0116128*
Y0116182*
Y0116236*
Y011629*
Y0116344*
Y0116398*
Y0116452*
Y0116506*
Y011656*
Y0116614*
Y0116668*
Y0116722*
Y0116776*
Y0116831*
Y0116885*
Y0116939*
Y0116993*
Y0117047*
Y0117101*
Y0117155*
Y0117209*
Y0117263*
Y0117317*
Y0117371*
Y0117425*
Y0117479*
Y0117533*
Y0117587*
Y0117641*
Y0117695*
X0594693*
Y011775*
X0662919*
Y0117695*
G37*
G36*
X0597125Y0080501D02*
X0597396D01*
Y0080447*
X0597558*
Y0080393*
X059772*
Y0080339*
X0597828*
Y0080285*
X0597936*
Y008023*
X059799*
Y0080177*
X0598099*
Y0080122*
X0598152*
Y0080068*
X0598207*
Y0080014*
X0598261*
Y007996*
X0598315*
Y0079906*
X0598369*
Y0079852*
X0598423*
Y0079798*
X0598477*
Y0079744*
X0598531*
Y007969*
Y0079636*
X0598585*
Y0079582*
X0598639*
Y0079528*
Y0079474*
X0598693*
Y007942*
Y0079365*
X0598747*
Y0079312*
Y0079257*
X0598801*
Y0079203*
Y0079149*
Y0079095*
X0598855*
Y0079041*
Y0078987*
Y0078933*
Y0078879*
X0598909*
Y0078825*
Y0078771*
Y0078717*
Y0078663*
Y0078609*
Y0078555*
Y00785*
Y0078447*
Y0078392*
Y0078338*
Y0078284*
Y007823*
Y0078176*
X0598855*
Y0078122*
Y0078068*
Y0078014*
Y007796*
X0598801*
Y0077906*
Y0077852*
Y0077798*
X0598747*
Y0077744*
Y007769*
Y0077636*
X0598693*
Y0077582*
Y0077527*
X0598639*
Y0077473*
X0598585*
Y0077419*
Y0077365*
X0598531*
Y0077311*
X0598477*
Y0077257*
Y0077203*
X0598423*
Y0077149*
X0598369*
Y0077095*
X0598315*
Y0077041*
X0598261*
Y0076987*
X0598207*
Y0076933*
X0598099*
Y0076879*
X0598044*
Y0076825*
X0597936*
Y0076771*
X0597882*
Y0076717*
X0597774*
Y0076662*
X0597612*
Y0076608*
X0597504*
Y0076554*
X0597288*
Y00765*
X0596477*
Y0076554*
X0596314*
Y0076608*
X0596152*
Y0076662*
X059599*
Y0076717*
X0595936*
Y0076771*
X0595828*
Y0076825*
X059572*
Y0076879*
X0595666*
Y0076933*
X0595612*
Y0076987*
X0595504*
Y0077041*
X0595449*
Y0077095*
X0595395*
Y0077149*
X0595341*
Y0077203*
Y0077257*
X0595287*
Y0077311*
X0595233*
Y0077365*
X0595179*
Y0077419*
Y0077473*
X0595125*
Y0077527*
Y0077582*
X0595071*
Y0077636*
Y007769*
X0595017*
Y0077744*
Y0077798*
X0594963*
Y0077852*
Y0077906*
Y007796*
X0594909*
Y0078014*
Y0078068*
Y0078122*
Y0078176*
Y007823*
X0594855*
Y0078284*
Y0078338*
Y0078392*
Y0078447*
Y00785*
Y0078555*
Y0078609*
Y0078663*
Y0078717*
Y0078771*
X0594909*
Y0078825*
Y0078879*
Y0078933*
Y0078987*
Y0079041*
X0594963*
Y0079095*
Y0079149*
Y0079203*
X0595017*
Y0079257*
Y0079312*
Y0079365*
X0595071*
Y007942*
Y0079474*
X0595125*
Y0079528*
Y0079582*
X0595179*
Y0079636*
X0595233*
Y007969*
Y0079744*
X0595287*
Y0079798*
X0595341*
Y0079852*
X0595395*
Y0079906*
X0595449*
Y007996*
X0595504*
Y0080014*
X0595558*
Y0080068*
X0595612*
Y0080122*
X0595666*
Y0080177*
X0595774*
Y008023*
X0595882*
Y0080285*
X0595936*
Y0080339*
X0596044*
Y0080393*
X0596206*
Y0080447*
X0596369*
Y0080501*
X0596639*
Y0080555*
X0597125*
Y0080501*
G37*
G36*
X0597342Y0073148D02*
X0597558D01*
Y0073094*
X0597666*
Y007304*
X0597774*
Y0072986*
X0597882*
Y0072932*
X059799*
Y0072878*
X0598044*
Y0072824*
X0598152*
Y007277*
X0598207*
Y0072716*
X0598261*
Y0072662*
X0598315*
Y0072608*
X0598369*
Y0072554*
X0598423*
Y00725*
X0598477*
Y0072446*
X0598531*
Y0072391*
Y0072338*
X0598585*
Y0072283*
X0598639*
Y0072229*
Y0072175*
X0598693*
Y0072121*
Y0072067*
X0598747*
Y0072013*
Y0071959*
X0598801*
Y0071905*
Y0071851*
Y0071797*
X0598855*
Y0071743*
Y0071689*
Y0071635*
Y0071581*
Y0071526*
X0598909*
Y0071473*
Y0071418*
Y0071364*
Y007131*
Y0071256*
Y0071202*
Y0071148*
Y0071094*
Y007104*
Y0070986*
Y0070932*
Y0070878*
X0598855*
Y0070824*
Y007077*
Y0070716*
Y0070662*
Y0070608*
X0598801*
Y0070553*
Y0070499*
Y0070445*
X0598747*
Y0070391*
Y0070337*
X0598693*
Y0070283*
Y0070229*
X0598639*
Y0070175*
Y0070121*
X0598585*
Y0070067*
X0598531*
Y0070013*
Y0069959*
X0598477*
Y0069905*
X0598423*
Y0069851*
X0598369*
Y0069797*
X0598315*
Y0069743*
X0598261*
Y0069688*
X0598207*
Y0069634*
X0598152*
Y006958*
X0598044*
Y0069526*
X059799*
Y0069472*
X0597882*
Y0069418*
X0597774*
Y0069364*
X0597666*
Y006931*
X0597504*
Y0069256*
X0597342*
Y0069202*
X0596423*
Y0069256*
X059626*
Y006931*
X0596098*
Y0069364*
X059599*
Y0069418*
X0595882*
Y0069472*
X0595774*
Y0069526*
X059572*
Y006958*
X0595666*
Y0069634*
X0595558*
Y0069688*
X0595504*
Y0069743*
X0595449*
Y0069797*
X0595395*
Y0069851*
X0595341*
Y0069905*
X0595287*
Y0069959*
Y0070013*
X0595233*
Y0070067*
X0595179*
Y0070121*
Y0070175*
X0595125*
Y0070229*
Y0070283*
X0595071*
Y0070337*
Y0070391*
X0595017*
Y0070445*
Y0070499*
X0594963*
Y0070553*
Y0070608*
Y0070662*
X0594909*
Y0070716*
Y007077*
Y0070824*
Y0070878*
Y0070932*
X0594855*
Y0070986*
Y007104*
Y0071094*
Y0071148*
Y0071202*
Y0071256*
Y007131*
Y0071364*
Y0071418*
Y0071473*
X0594909*
Y0071526*
Y0071581*
Y0071635*
Y0071689*
Y0071743*
X0594963*
Y0071797*
Y0071851*
Y0071905*
X0595017*
Y0071959*
Y0072013*
X0595071*
Y0072067*
Y0072121*
X0595125*
Y0072175*
Y0072229*
X0595179*
Y0072283*
Y0072338*
X0595233*
Y0072391*
X0595287*
Y0072446*
Y00725*
X0595341*
Y0072554*
X0595395*
Y0072608*
X0595449*
Y0072662*
X0595504*
Y0072716*
X0595558*
Y007277*
X0595612*
Y0072824*
X059572*
Y0072878*
X0595774*
Y0072932*
X0595882*
Y0072986*
X059599*
Y007304*
X0596098*
Y0073094*
X059626*
Y0073148*
X0596423*
Y0073203*
X0597342*
Y0073148*
G37*
G36*
X057874Y0067913D02*
X0378937D01*
Y0267717*
X057874*
Y0067913*
G37*
G36*
X0589449Y0117695D02*
X0589989D01*
Y0117641*
X0590205*
Y0117587*
X0590422*
Y0117533*
X059053*
Y0117479*
X0590692*
Y0117425*
X05908*
Y0117371*
X0590908*
Y0117317*
X0591016*
Y0117263*
X0591124*
Y0117209*
X0591179*
Y0117155*
X0591287*
Y0117101*
X0591341*
Y0117047*
X0591395*
Y0116993*
X0591503*
Y0116939*
X0591557*
Y0116885*
X0591611*
Y0116831*
X0591665*
Y0116776*
X0591719*
Y0116722*
X0591773*
Y0116668*
X0591827*
Y0116614*
X0591881*
Y011656*
X0591935*
Y0116506*
Y0116452*
X059199*
Y0116398*
X0592043*
Y0116344*
X0592098*
Y011629*
Y0116236*
X0592152*
Y0116182*
X0592206*
Y0116128*
Y0116074*
X059226*
Y011602*
Y0115965*
X0592314*
Y0115911*
Y0115857*
X0592368*
Y0115803*
Y0115749*
X0592422*
Y0115695*
Y0115641*
Y0115587*
X0592476*
Y0115533*
Y0115479*
X059253*
Y0115425*
Y0115371*
Y0115317*
Y0115263*
X0592584*
Y0115209*
Y0115155*
Y0115101*
Y0115047*
Y0114992*
X0592638*
Y0114938*
Y0114884*
Y011483*
Y0114776*
Y0114722*
Y0114668*
Y0114614*
Y011456*
Y0114506*
Y0114452*
Y0114398*
Y0114344*
Y011429*
Y0114235*
Y0114181*
Y0114127*
Y0114073*
Y0114019*
Y0113965*
Y0113911*
Y0113857*
Y0113803*
Y0113749*
Y0113695*
Y0113641*
Y0113587*
Y0113533*
Y0113479*
Y0113425*
Y0113371*
Y0113317*
Y0113262*
Y0113208*
Y0113154*
Y01131*
Y0113046*
Y0112992*
Y0112938*
Y0112884*
Y011283*
Y0112776*
Y0112722*
Y0112668*
Y0112614*
Y011256*
Y0112505*
Y0112452*
Y0112397*
Y0112343*
Y0112289*
Y0112235*
Y0112181*
Y0112127*
Y0112073*
Y0112019*
Y0111965*
Y0111911*
Y0111857*
Y0111803*
Y0111749*
Y0111695*
Y0111641*
Y0111586*
Y0111532*
Y0111478*
Y0111424*
Y011137*
Y0111316*
Y0111262*
Y0111208*
Y0111154*
Y01111*
Y0111046*
Y0110992*
Y0110938*
Y0110884*
Y011083*
Y0110776*
Y0110722*
Y0110668*
Y0110613*
Y0110559*
Y0110505*
Y0110451*
Y0110397*
Y0110343*
Y0110289*
Y0110235*
Y0110181*
Y0110127*
Y0110073*
Y0110019*
Y0109965*
Y0109911*
Y0109856*
Y0109802*
Y0109748*
Y0109694*
Y010964*
Y0109586*
Y0109532*
Y0109478*
Y0109424*
Y010937*
Y0109316*
Y0109262*
Y0109208*
Y0109154*
Y01091*
Y0109046*
Y0108992*
Y0108938*
Y0108883*
Y0108829*
Y0108775*
Y0108721*
Y0108667*
Y0108613*
Y0108559*
Y0108505*
Y0108451*
Y0108397*
Y0108343*
Y0108289*
Y0108235*
Y0108181*
Y0108126*
Y0108072*
Y0108018*
Y0107964*
Y010791*
Y0107856*
Y0107802*
Y0107748*
Y0107694*
Y010764*
Y0107586*
Y0107532*
Y0107478*
Y0107424*
Y010737*
Y0107316*
Y0107262*
Y0107208*
Y0107153*
Y0107099*
Y0107045*
Y0106991*
Y0106937*
Y0106883*
Y0106829*
Y0106775*
Y0106721*
Y0106667*
Y0106613*
Y0106559*
Y0106505*
Y0106451*
Y0106397*
Y0106342*
Y0106288*
Y0106234*
Y010618*
Y0106126*
Y0106072*
Y0106018*
Y0105964*
Y010591*
Y0105856*
Y0105802*
Y0105748*
Y0105694*
Y010564*
Y0105586*
Y0105532*
Y0105477*
Y0105423*
Y0105369*
Y0105315*
Y0105261*
Y0105207*
Y0105153*
Y0105099*
Y0105045*
Y0104991*
Y0104937*
Y0104883*
Y0104829*
Y0104775*
Y0104721*
Y0104667*
Y0104613*
Y0104558*
Y0104504*
Y010445*
Y0104396*
Y0104342*
Y0104288*
Y0104234*
Y010418*
Y0104126*
Y0104072*
Y0104018*
Y0103964*
Y010391*
Y0103856*
Y0103802*
Y0103747*
Y0103693*
Y0103639*
Y0103585*
Y0103531*
Y0103477*
Y0103423*
Y0103369*
Y0103315*
Y0103261*
Y0103207*
Y0103153*
Y0103099*
Y0103045*
Y0102991*
Y0102937*
Y0102883*
Y0102828*
Y0102774*
Y010272*
Y0102666*
Y0102612*
Y0102558*
Y0102504*
Y010245*
Y0102396*
Y0102342*
Y0102288*
Y0102234*
Y010218*
Y0102126*
Y0102072*
Y0102017*
Y0101963*
Y0101909*
Y0101855*
Y0101801*
Y0101747*
Y0101693*
Y0101639*
Y0101585*
Y0101531*
Y0101477*
Y0101423*
Y0101369*
Y0101315*
Y0101261*
Y0101207*
Y0101153*
Y0101099*
Y0101044*
Y010099*
Y0100936*
Y0100882*
Y0100828*
Y0100774*
Y010072*
Y0100666*
Y0100612*
Y0100558*
Y0100504*
Y010045*
Y0100396*
Y0100342*
Y0100287*
Y0100233*
Y0100179*
Y0100125*
Y0100071*
Y0100017*
Y0099963*
Y0099909*
Y0099855*
Y0099801*
Y0099747*
Y0099693*
Y0099639*
Y0099585*
Y0099531*
Y0099477*
Y0099423*
Y0099369*
Y0099314*
Y009926*
Y0099206*
Y0099152*
Y0099098*
Y0099044*
Y009899*
Y0098936*
Y0098882*
Y0098828*
Y0098774*
Y009872*
Y0098666*
Y0098612*
Y0098558*
Y0098504*
Y0098449*
Y0098395*
Y0098341*
Y0098287*
Y0098233*
Y0098179*
Y0098125*
Y0098071*
Y0098017*
Y0097963*
Y0097909*
Y0097855*
Y0097801*
Y0097747*
Y0097693*
Y0097638*
Y0097584*
Y009753*
Y0097476*
Y0097422*
Y0097368*
Y0097314*
Y009726*
Y0097206*
Y0097152*
Y0097098*
Y0097044*
Y009699*
Y0096936*
Y0096882*
Y0096828*
Y0096773*
Y0096719*
Y0096665*
Y0096611*
Y0096557*
Y0096503*
Y0096449*
Y0096395*
Y0096341*
Y0096287*
Y0096233*
Y0096179*
Y0096125*
Y0096071*
Y0096017*
Y0095963*
Y0095908*
Y0095854*
Y00958*
Y0095746*
Y0095692*
Y0095638*
Y0095584*
Y009553*
Y0095476*
Y0095422*
Y0095368*
Y0095314*
Y009526*
Y0095206*
Y0095152*
Y0095098*
Y0095043*
Y009499*
Y0094935*
Y0094881*
Y0094827*
Y0094773*
Y0094719*
Y0094665*
Y0094611*
Y0094557*
Y0094503*
Y0094449*
Y0094395*
Y0094341*
Y0094287*
Y0094233*
Y0094178*
Y0094125*
Y009407*
Y0094016*
Y0093962*
Y0093908*
Y0093854*
Y00938*
Y0093746*
Y0093692*
Y0093638*
Y0093584*
Y009353*
Y0093476*
Y0093422*
Y0093368*
Y0093313*
Y009326*
Y0093205*
Y0093151*
Y0093097*
Y0093043*
Y0092989*
Y0092935*
Y0092881*
Y0092827*
Y0092773*
Y0092719*
Y0092665*
Y0092611*
Y0092557*
Y0092503*
Y0092449*
Y0092395*
Y009234*
Y0092286*
Y0092232*
Y0092178*
Y0092124*
Y009207*
Y0092016*
Y0091962*
Y0091908*
Y0091854*
Y00918*
Y0091746*
Y0091692*
Y0091638*
Y0091584*
Y009153*
Y0091475*
Y0091421*
Y0091367*
Y0091313*
Y0091259*
Y0091205*
Y0091151*
Y0091097*
Y0091043*
Y0090989*
Y0090935*
Y0090881*
Y0090827*
Y0090773*
Y0090719*
Y0090664*
Y009061*
Y0090556*
Y0090502*
Y0090448*
Y0090394*
Y009034*
Y0090286*
Y0090232*
Y0090178*
Y0090124*
Y009007*
Y0090016*
Y0089962*
Y0089908*
Y0089854*
Y0089799*
Y0089745*
Y0089691*
Y0089637*
Y0089583*
Y0089529*
Y0089475*
Y0089421*
Y0089367*
Y0089313*
Y0089259*
Y0089205*
Y0089151*
Y0089097*
Y0089043*
Y0088989*
Y0088934*
Y008888*
Y0088826*
Y0088772*
Y0088718*
Y0088664*
Y008861*
Y0088556*
Y0088502*
Y0088448*
Y0088394*
Y008834*
Y0088286*
Y0088232*
Y0088178*
Y0088124*
Y0088069*
Y0088016*
Y0087961*
Y0087907*
Y0087853*
Y0087799*
Y0087745*
Y0087691*
Y0087637*
Y0087583*
Y0087529*
Y0087475*
Y0087421*
Y0087367*
Y0087313*
Y0087259*
Y0087204*
Y0087151*
Y0087096*
Y0087042*
Y0086988*
Y0086934*
Y008688*
Y0086826*
Y0086772*
Y0086718*
Y0086664*
Y008661*
Y0086556*
Y0086502*
Y0086448*
Y0086394*
Y0086339*
Y0086286*
Y0086231*
Y0086177*
Y0086123*
Y0086069*
Y0086015*
Y0085961*
Y0085907*
Y0085853*
Y0085799*
Y0085745*
Y0085691*
Y0085637*
Y0085583*
Y0085529*
Y0085474*
Y0085421*
Y0085366*
Y0085312*
Y0085258*
Y0085204*
Y008515*
Y0085096*
Y0085042*
Y0084988*
Y0084934*
Y008488*
Y0084826*
Y0084772*
Y0084718*
Y0084664*
Y008461*
Y0084556*
Y0084501*
Y0084447*
Y0084393*
Y0084339*
Y0084285*
Y0084231*
Y0084177*
Y0084123*
Y0084069*
Y0084015*
Y0083961*
Y0083907*
Y0083853*
Y0083799*
Y0083745*
Y0083691*
Y0083636*
Y0083582*
Y0083528*
Y0083474*
Y008342*
Y0083366*
Y0083312*
Y0083258*
Y0083204*
Y008315*
Y0083096*
Y0083042*
Y0082988*
Y0082934*
Y008288*
Y0082825*
Y0082771*
Y0082717*
Y0082663*
Y0082609*
Y0082555*
Y0082501*
Y0082447*
Y0082393*
Y0082339*
Y0082285*
Y0082231*
Y0082177*
Y0082123*
Y0082069*
Y0082015*
Y008196*
Y0081906*
Y0081852*
Y0081798*
Y0081744*
Y008169*
Y0081636*
Y0081582*
Y0081528*
Y0081474*
Y008142*
Y0081366*
Y0081312*
Y0081258*
Y0081204*
Y008115*
Y0081095*
Y0081042*
Y0080987*
Y0080933*
Y0080879*
Y0080825*
Y0080771*
Y0080717*
Y0080663*
Y0080609*
Y0080555*
Y0080501*
Y0080447*
Y0080393*
Y0080339*
Y0080285*
Y008023*
Y0080177*
Y0080122*
Y0080068*
Y0080014*
Y007996*
Y0079906*
Y0079852*
Y0079798*
Y0079744*
Y007969*
Y0079636*
Y0079582*
Y0079528*
Y0079474*
Y007942*
Y0079365*
Y0079312*
Y0079257*
Y0079203*
Y0079149*
Y0079095*
Y0079041*
Y0078987*
Y0078933*
Y0078879*
Y0078825*
Y0078771*
Y0078717*
Y0078663*
Y0078609*
Y0078555*
Y00785*
Y0078447*
Y0078392*
Y0078338*
Y0078284*
Y007823*
Y0078176*
Y0078122*
Y0078068*
Y0078014*
Y007796*
Y0077906*
Y0077852*
Y0077798*
Y0077744*
Y007769*
Y0077636*
Y0077582*
Y0077527*
Y0077473*
Y0077419*
Y0077365*
Y0077311*
Y0077257*
Y0077203*
Y0077149*
Y0077095*
Y0077041*
Y0076987*
Y0076933*
Y0076879*
Y0076825*
Y0076771*
Y0076717*
Y0076662*
Y0076608*
Y0076554*
Y00765*
Y0076446*
Y0076392*
Y0076338*
Y0076284*
Y007623*
Y0076176*
Y0076122*
Y0076068*
Y0076014*
Y007596*
Y0075906*
Y0075852*
Y0075797*
Y0075743*
Y0075689*
Y0075635*
Y0075581*
Y0075527*
Y0075473*
Y0075419*
Y0075365*
Y0075311*
Y0075257*
Y0075203*
Y0075149*
Y0075095*
Y0075041*
Y0074986*
Y0074932*
Y0074878*
Y0074824*
Y007477*
Y0074716*
Y0074662*
Y0074608*
Y0074554*
Y00745*
Y0074446*
Y0074392*
Y0074338*
Y0074284*
Y007423*
Y0074176*
Y0074121*
Y0074067*
Y0074013*
Y0073959*
Y0073905*
Y0073851*
Y0073797*
Y0073743*
Y0073689*
Y0073635*
Y0073581*
Y0073527*
Y0073473*
Y0073419*
Y0073365*
Y0073311*
Y0073256*
Y0073203*
Y0073148*
Y0073094*
Y007304*
Y0072986*
Y0072932*
Y0072878*
Y0072824*
Y007277*
Y0072716*
Y0072662*
Y0072608*
Y0072554*
Y00725*
Y0072446*
Y0072391*
Y0072338*
Y0072283*
Y0072229*
Y0072175*
Y0072121*
Y0072067*
Y0072013*
Y0071959*
Y0071905*
Y0071851*
Y0071797*
Y0071743*
Y0071689*
Y0071635*
Y0071581*
Y0071526*
Y0071473*
Y0071418*
Y0071364*
Y007131*
Y0071256*
Y0071202*
Y0071148*
Y0071094*
Y007104*
Y0070986*
Y0070932*
Y0070878*
Y0070824*
Y007077*
Y0070716*
Y0070662*
Y0070608*
Y0070553*
Y0070499*
Y0070445*
Y0070391*
Y0070337*
Y0070283*
Y0070229*
Y0070175*
Y0070121*
Y0070067*
Y0070013*
Y0069959*
Y0069905*
Y0069851*
Y0069797*
Y0069743*
Y0069688*
Y0069634*
Y006958*
Y0069526*
Y0069472*
Y0069418*
Y0069364*
Y006931*
Y0069256*
Y0069202*
Y0069148*
Y0069094*
Y006904*
Y0068986*
Y0068932*
Y0068878*
Y0068823*
Y0068769*
Y0068715*
Y0068661*
Y0068607*
Y0068553*
Y0068499*
Y0068445*
Y0068391*
Y0068337*
Y0068283*
Y0068229*
Y0068175*
Y0068121*
Y0068067*
Y0068012*
Y0067958*
Y0067904*
Y006785*
Y0067796*
Y0067742*
Y0067688*
Y0067634*
Y006758*
Y0067526*
Y0067472*
Y0067418*
Y0067364*
Y006731*
Y0067256*
Y0067202*
Y0067147*
Y0067093*
Y0067039*
Y0066985*
Y0066931*
Y0066877*
Y0066823*
Y0066769*
Y0066715*
Y0066661*
Y0066607*
Y0066553*
Y0066499*
Y0066445*
Y0066391*
Y0066337*
Y0066282*
Y0066228*
Y0066174*
Y006612*
Y0066066*
Y0066012*
Y0065958*
Y0065904*
Y006585*
Y0065796*
Y0065742*
Y0065688*
Y0065634*
Y006558*
Y0065526*
Y0065472*
Y0065417*
Y0065364*
Y0065309*
Y0065255*
Y0065201*
Y0065147*
Y0065093*
Y0065039*
Y0064985*
Y0064931*
Y0064877*
Y0064823*
Y0064769*
Y0064715*
Y0064661*
Y0064607*
Y0064552*
Y0064499*
Y0064444*
Y006439*
Y0064336*
Y0064282*
Y0064228*
Y0064174*
Y006412*
Y0064066*
Y0064012*
Y0063958*
Y0063904*
Y006385*
Y0063796*
Y0063742*
Y0063688*
Y0063634*
Y0063579*
Y0063525*
Y0063471*
Y0063417*
Y0063363*
Y0063309*
Y0063255*
Y0063201*
Y0063147*
Y0063093*
Y0063039*
Y0062985*
Y0062931*
Y0062877*
Y0062823*
Y0062769*
Y0062714*
Y006266*
Y0062606*
Y0062552*
Y0062498*
Y0062444*
Y006239*
Y0062336*
Y0062282*
Y0062228*
Y0062174*
Y006212*
Y0062066*
Y0062012*
Y0061958*
Y0061904*
Y0061849*
Y0061795*
Y0061741*
Y0061687*
Y0061633*
Y0061579*
Y0061525*
Y0061471*
Y0061417*
Y0061363*
Y0061309*
Y0061255*
Y0061201*
Y0061147*
Y0061093*
Y0061039*
Y0060984*
Y006093*
Y0060876*
Y0060822*
Y0060768*
Y0060714*
Y006066*
Y0060606*
Y0060552*
Y0060498*
Y0060444*
Y006039*
Y0060336*
Y0060282*
Y0060228*
Y0060173*
Y0060119*
Y0060065*
Y0060011*
Y0059957*
Y0059903*
Y0059849*
Y0059795*
Y0059741*
Y0059687*
Y0059633*
Y0059579*
Y0059525*
Y0059471*
Y0059417*
Y0059363*
Y0059308*
Y0059254*
Y00592*
Y0059146*
Y0059092*
Y0059038*
Y0058984*
Y005893*
Y0058876*
Y0058822*
Y0058768*
Y0058714*
Y005866*
Y0058606*
Y0058552*
Y0058498*
Y0058443*
Y005839*
Y0058335*
Y0058281*
Y0058227*
Y0058173*
Y0058119*
Y0058065*
Y0058011*
Y0057957*
Y0057903*
Y0057849*
Y0057795*
Y0057741*
Y0057687*
Y0057633*
Y0057578*
Y0057525*
Y005747*
Y0057416*
Y0057362*
Y0057308*
Y0057254*
Y00572*
Y0057146*
Y0057092*
Y0057038*
Y0056984*
Y005693*
Y0056876*
Y0056822*
Y0056768*
Y0056714*
Y005666*
Y0056605*
Y0056551*
Y0056497*
Y0056443*
Y0056389*
Y0056335*
Y0056281*
Y0056227*
Y0056173*
Y0056119*
Y0056065*
Y0056011*
Y0055957*
X0590638*
Y0056011*
Y0056065*
Y0056119*
Y0056173*
Y0056227*
Y0056281*
Y0056335*
Y0056389*
Y0056443*
Y0056497*
Y0056551*
Y0056605*
Y005666*
Y0056714*
Y0056768*
Y0056822*
Y0056876*
Y005693*
Y0056984*
Y0057038*
Y0057092*
Y0057146*
Y00572*
Y0057254*
Y0057308*
Y0057362*
Y0057416*
Y005747*
Y0057525*
Y0057578*
Y0057633*
Y0057687*
Y0057741*
Y0057795*
Y0057849*
Y0057903*
Y0057957*
Y0058011*
Y0058065*
Y0058119*
Y0058173*
Y0058227*
Y0058281*
Y0058335*
Y005839*
Y0058443*
Y0058498*
Y0058552*
Y0058606*
Y005866*
Y0058714*
Y0058768*
Y0058822*
Y0058876*
Y005893*
Y0058984*
Y0059038*
Y0059092*
Y0059146*
Y00592*
Y0059254*
Y0059308*
Y0059363*
Y0059417*
Y0059471*
Y0059525*
Y0059579*
Y0059633*
Y0059687*
Y0059741*
Y0059795*
Y0059849*
Y0059903*
Y0059957*
Y0060011*
Y0060065*
Y0060119*
Y0060173*
Y0060228*
Y0060282*
Y0060336*
Y006039*
Y0060444*
Y0060498*
Y0060552*
Y0060606*
Y006066*
Y0060714*
Y0060768*
Y0060822*
Y0060876*
Y006093*
Y0060984*
Y0061039*
Y0061093*
Y0061147*
Y0061201*
Y0061255*
Y0061309*
Y0061363*
Y0061417*
Y0061471*
Y0061525*
Y0061579*
Y0061633*
Y0061687*
Y0061741*
Y0061795*
Y0061849*
Y0061904*
Y0061958*
Y0062012*
Y0062066*
Y006212*
Y0062174*
Y0062228*
Y0062282*
Y0062336*
Y006239*
Y0062444*
Y0062498*
Y0062552*
Y0062606*
Y006266*
Y0062714*
Y0062769*
Y0062823*
Y0062877*
Y0062931*
Y0062985*
Y0063039*
Y0063093*
Y0063147*
Y0063201*
Y0063255*
Y0063309*
Y0063363*
Y0063417*
Y0063471*
Y0063525*
Y0063579*
Y0063634*
Y0063688*
Y0063742*
Y0063796*
Y006385*
Y0063904*
Y0063958*
Y0064012*
Y0064066*
Y006412*
Y0064174*
Y0064228*
Y0064282*
Y0064336*
Y006439*
Y0064444*
Y0064499*
Y0064552*
Y0064607*
Y0064661*
Y0064715*
Y0064769*
Y0064823*
Y0064877*
Y0064931*
Y0064985*
Y0065039*
Y0065093*
Y0065147*
Y0065201*
Y0065255*
Y0065309*
Y0065364*
Y0065417*
Y0065472*
Y0065526*
Y006558*
Y0065634*
Y0065688*
Y0065742*
Y0065796*
Y006585*
Y0065904*
Y0065958*
Y0066012*
Y0066066*
Y006612*
Y0066174*
Y0066228*
Y0066282*
Y0066337*
Y0066391*
Y0066445*
Y0066499*
Y0066553*
Y0066607*
Y0066661*
Y0066715*
Y0066769*
Y0066823*
Y0066877*
Y0066931*
Y0066985*
Y0067039*
Y0067093*
Y0067147*
Y0067202*
Y0067256*
Y006731*
Y0067364*
Y0067418*
Y0067472*
Y0067526*
Y006758*
Y0067634*
Y0067688*
Y0067742*
Y0067796*
Y006785*
Y0067904*
Y0067958*
Y0068012*
Y0068067*
Y0068121*
Y0068175*
Y0068229*
Y0068283*
Y0068337*
Y0068391*
Y0068445*
Y0068499*
Y0068553*
Y0068607*
Y0068661*
Y0068715*
Y0068769*
Y0068823*
Y0068878*
Y0068932*
Y0068986*
Y006904*
Y0069094*
Y0069148*
Y0069202*
Y0069256*
Y006931*
Y0069364*
Y0069418*
Y0069472*
Y0069526*
Y006958*
Y0069634*
Y0069688*
Y0069743*
Y0069797*
Y0069851*
Y0069905*
Y0069959*
Y0070013*
Y0070067*
Y0070121*
Y0070175*
Y0070229*
Y0070283*
Y0070337*
Y0070391*
Y0070445*
Y0070499*
Y0070553*
Y0070608*
Y0070662*
Y0070716*
Y007077*
Y0070824*
Y0070878*
Y0070932*
Y0070986*
Y007104*
Y0071094*
Y0071148*
Y0071202*
Y0071256*
Y007131*
Y0071364*
Y0071418*
Y0071473*
Y0071526*
Y0071581*
Y0071635*
Y0071689*
Y0071743*
Y0071797*
Y0071851*
Y0071905*
Y0071959*
Y0072013*
Y0072067*
Y0072121*
Y0072175*
Y0072229*
Y0072283*
Y0072338*
Y0072391*
Y0072446*
Y00725*
Y0072554*
Y0072608*
Y0072662*
Y0072716*
Y007277*
Y0072824*
Y0072878*
Y0072932*
Y0072986*
Y007304*
Y0073094*
Y0073148*
Y0073203*
Y0073256*
Y0073311*
Y0073365*
Y0073419*
Y0073473*
Y0073527*
Y0073581*
Y0073635*
Y0073689*
Y0073743*
Y0073797*
Y0073851*
Y0073905*
Y0073959*
Y0074013*
Y0074067*
Y0074121*
Y0074176*
Y007423*
Y0074284*
Y0074338*
Y0074392*
Y0074446*
Y00745*
Y0074554*
Y0074608*
Y0074662*
Y0074716*
Y007477*
Y0074824*
Y0074878*
Y0074932*
Y0074986*
Y0075041*
Y0075095*
Y0075149*
Y0075203*
Y0075257*
Y0075311*
Y0075365*
Y0075419*
Y0075473*
Y0075527*
Y0075581*
Y0075635*
Y0075689*
Y0075743*
Y0075797*
Y0075852*
Y0075906*
Y007596*
Y0076014*
Y0076068*
Y0076122*
Y0076176*
Y007623*
Y0076284*
Y0076338*
Y0076392*
Y0076446*
Y00765*
Y0076554*
Y0076608*
Y0076662*
Y0076717*
Y0076771*
Y0076825*
Y0076879*
Y0076933*
Y0076987*
Y0077041*
Y0077095*
Y0077149*
Y0077203*
Y0077257*
Y0077311*
Y0077365*
Y0077419*
Y0077473*
Y0077527*
Y0077582*
Y0077636*
Y007769*
Y0077744*
Y0077798*
Y0077852*
Y0077906*
Y007796*
Y0078014*
Y0078068*
Y0078122*
Y0078176*
Y007823*
Y0078284*
Y0078338*
Y0078392*
Y0078447*
Y00785*
Y0078555*
Y0078609*
Y0078663*
Y0078717*
Y0078771*
Y0078825*
Y0078879*
Y0078933*
Y0078987*
Y0079041*
Y0079095*
Y0079149*
Y0079203*
Y0079257*
Y0079312*
Y0079365*
Y007942*
Y0079474*
Y0079528*
Y0079582*
Y0079636*
Y007969*
Y0079744*
Y0079798*
Y0079852*
Y0079906*
Y007996*
Y0080014*
Y0080068*
Y0080122*
Y0080177*
Y008023*
Y0080285*
Y0080339*
Y0080393*
Y0080447*
Y0080501*
Y0080555*
Y0080609*
Y0080663*
Y0080717*
Y0080771*
Y0080825*
Y0080879*
Y0080933*
Y0080987*
Y0081042*
Y0081095*
Y008115*
Y0081204*
Y0081258*
Y0081312*
Y0081366*
Y008142*
Y0081474*
Y0081528*
Y0081582*
Y0081636*
Y008169*
Y0081744*
Y0081798*
Y0081852*
Y0081906*
Y008196*
Y0082015*
Y0082069*
Y0082123*
Y0082177*
Y0082231*
Y0082285*
Y0082339*
Y0082393*
Y0082447*
Y0082501*
Y0082555*
Y0082609*
Y0082663*
Y0082717*
Y0082771*
Y0082825*
Y008288*
Y0082934*
Y0082988*
Y0083042*
Y0083096*
Y008315*
Y0083204*
Y0083258*
Y0083312*
Y0083366*
Y008342*
Y0083474*
Y0083528*
Y0083582*
Y0083636*
Y0083691*
Y0083745*
Y0083799*
Y0083853*
Y0083907*
Y0083961*
Y0084015*
Y0084069*
Y0084123*
Y0084177*
Y0084231*
Y0084285*
Y0084339*
Y0084393*
Y0084447*
Y0084501*
Y0084556*
Y008461*
Y0084664*
Y0084718*
Y0084772*
Y0084826*
Y008488*
Y0084934*
Y0084988*
Y0085042*
Y0085096*
Y008515*
Y0085204*
Y0085258*
Y0085312*
Y0085366*
Y0085421*
Y0085474*
Y0085529*
Y0085583*
Y0085637*
Y0085691*
Y0085745*
Y0085799*
Y0085853*
Y0085907*
Y0085961*
Y0086015*
Y0086069*
Y0086123*
Y0086177*
Y0086231*
Y0086286*
Y0086339*
Y0086394*
Y0086448*
Y0086502*
Y0086556*
Y008661*
Y0086664*
Y0086718*
Y0086772*
Y0086826*
Y008688*
Y0086934*
Y0086988*
Y0087042*
Y0087096*
Y0087151*
Y0087204*
Y0087259*
Y0087313*
Y0087367*
Y0087421*
Y0087475*
Y0087529*
Y0087583*
Y0087637*
Y0087691*
Y0087745*
Y0087799*
Y0087853*
Y0087907*
Y0087961*
Y0088016*
Y0088069*
Y0088124*
Y0088178*
Y0088232*
Y0088286*
Y008834*
Y0088394*
Y0088448*
Y0088502*
Y0088556*
Y008861*
Y0088664*
Y0088718*
Y0088772*
Y0088826*
Y008888*
Y0088934*
Y0088989*
Y0089043*
Y0089097*
Y0089151*
Y0089205*
Y0089259*
Y0089313*
Y0089367*
Y0089421*
Y0089475*
Y0089529*
Y0089583*
Y0089637*
Y0089691*
Y0089745*
Y0089799*
Y0089854*
Y0089908*
Y0089962*
Y0090016*
Y009007*
Y0090124*
Y0090178*
Y0090232*
Y0090286*
Y009034*
Y0090394*
Y0090448*
Y0090502*
Y0090556*
Y009061*
Y0090664*
Y0090719*
Y0090773*
Y0090827*
Y0090881*
Y0090935*
Y0090989*
Y0091043*
Y0091097*
Y0091151*
Y0091205*
Y0091259*
Y0091313*
Y0091367*
Y0091421*
Y0091475*
Y009153*
Y0091584*
Y0091638*
Y0091692*
Y0091746*
Y00918*
Y0091854*
Y0091908*
Y0091962*
Y0092016*
Y009207*
Y0092124*
Y0092178*
Y0092232*
Y0092286*
Y009234*
Y0092395*
Y0092449*
Y0092503*
Y0092557*
Y0092611*
Y0092665*
Y0092719*
Y0092773*
Y0092827*
Y0092881*
Y0092935*
Y0092989*
Y0093043*
Y0093097*
Y0093151*
Y0093205*
Y009326*
Y0093313*
Y0093368*
Y0093422*
Y0093476*
Y009353*
Y0093584*
Y0093638*
Y0093692*
Y0093746*
Y00938*
Y0093854*
Y0093908*
Y0093962*
Y0094016*
Y009407*
Y0094125*
Y0094178*
Y0094233*
Y0094287*
Y0094341*
Y0094395*
Y0094449*
Y0094503*
Y0094557*
Y0094611*
Y0094665*
Y0094719*
Y0094773*
Y0094827*
Y0094881*
Y0094935*
Y009499*
Y0095043*
Y0095098*
Y0095152*
Y0095206*
Y009526*
Y0095314*
Y0095368*
Y0095422*
Y0095476*
Y009553*
Y0095584*
Y0095638*
Y0095692*
Y0095746*
Y00958*
Y0095854*
Y0095908*
Y0095963*
Y0096017*
Y0096071*
Y0096125*
Y0096179*
Y0096233*
Y0096287*
Y0096341*
Y0096395*
Y0096449*
Y0096503*
Y0096557*
Y0096611*
Y0096665*
Y0096719*
Y0096773*
Y0096828*
Y0096882*
Y0096936*
Y009699*
Y0097044*
Y0097098*
Y0097152*
Y0097206*
Y009726*
Y0097314*
Y0097368*
Y0097422*
Y0097476*
Y009753*
Y0097584*
Y0097638*
Y0097693*
Y0097747*
Y0097801*
Y0097855*
Y0097909*
Y0097963*
Y0098017*
Y0098071*
Y0098125*
Y0098179*
Y0098233*
Y0098287*
Y0098341*
Y0098395*
Y0098449*
Y0098504*
Y0098558*
Y0098612*
Y0098666*
Y009872*
Y0098774*
Y0098828*
Y0098882*
Y0098936*
Y009899*
Y0099044*
Y0099098*
Y0099152*
Y0099206*
Y009926*
Y0099314*
Y0099369*
Y0099423*
Y0099477*
Y0099531*
Y0099585*
Y0099639*
Y0099693*
Y0099747*
Y0099801*
Y0099855*
Y0099909*
Y0099963*
Y0100017*
Y0100071*
Y0100125*
Y0100179*
Y0100233*
Y0100287*
Y0100342*
Y0100396*
Y010045*
Y0100504*
Y0100558*
Y0100612*
Y0100666*
Y010072*
Y0100774*
Y0100828*
Y0100882*
Y0100936*
Y010099*
Y0101044*
Y0101099*
Y0101153*
Y0101207*
Y0101261*
Y0101315*
Y0101369*
Y0101423*
Y0101477*
Y0101531*
Y0101585*
Y0101639*
Y0101693*
Y0101747*
Y0101801*
Y0101855*
Y0101909*
Y0101963*
Y0102017*
Y0102072*
Y0102126*
Y010218*
Y0102234*
Y0102288*
Y0102342*
Y0102396*
Y010245*
Y0102504*
Y0102558*
Y0102612*
Y0102666*
Y010272*
Y0102774*
Y0102828*
Y0102883*
Y0102937*
Y0102991*
Y0103045*
Y0103099*
Y0103153*
Y0103207*
Y0103261*
Y0103315*
Y0103369*
Y0103423*
Y0103477*
Y0103531*
Y0103585*
Y0103639*
Y0103693*
Y0103747*
Y0103802*
Y0103856*
Y010391*
Y0103964*
Y0104018*
Y0104072*
Y0104126*
Y010418*
Y0104234*
Y0104288*
Y0104342*
Y0104396*
Y010445*
Y0104504*
Y0104558*
Y0104613*
Y0104667*
Y0104721*
Y0104775*
Y0104829*
Y0104883*
Y0104937*
Y0104991*
Y0105045*
Y0105099*
Y0105153*
Y0105207*
Y0105261*
Y0105315*
Y0105369*
Y0105423*
Y0105477*
Y0105532*
Y0105586*
Y010564*
Y0105694*
Y0105748*
Y0105802*
Y0105856*
Y010591*
Y0105964*
Y0106018*
Y0106072*
Y0106126*
Y010618*
Y0106234*
Y0106288*
Y0106342*
Y0106397*
Y0106451*
Y0106505*
Y0106559*
Y0106613*
Y0106667*
Y0106721*
Y0106775*
Y0106829*
Y0106883*
Y0106937*
Y0106991*
Y0107045*
Y0107099*
Y0107153*
Y0107208*
Y0107262*
Y0107316*
Y010737*
Y0107424*
Y0107478*
Y0107532*
Y0107586*
Y010764*
Y0107694*
Y0107748*
Y0107802*
Y0107856*
Y010791*
Y0107964*
Y0108018*
Y0108072*
Y0108126*
Y0108181*
Y0108235*
Y0108289*
Y0108343*
Y0108397*
Y0108451*
Y0108505*
Y0108559*
Y0108613*
Y0108667*
Y0108721*
Y0108775*
Y0108829*
Y0108883*
Y0108938*
Y0108992*
Y0109046*
Y01091*
Y0109154*
Y0109208*
Y0109262*
Y0109316*
Y010937*
Y0109424*
Y0109478*
Y0109532*
Y0109586*
Y010964*
Y0109694*
Y0109748*
Y0109802*
Y0109856*
Y0109911*
Y0109965*
Y0110019*
Y0110073*
Y0110127*
Y0110181*
Y0110235*
Y0110289*
Y0110343*
Y0110397*
Y0110451*
Y0110505*
Y0110559*
Y0110613*
Y0110668*
Y0110722*
Y0110776*
Y011083*
Y0110884*
Y0110938*
Y0110992*
Y0111046*
Y01111*
Y0111154*
Y0111208*
Y0111262*
Y0111316*
Y011137*
Y0111424*
Y0111478*
Y0111532*
Y0111586*
Y0111641*
Y0111695*
Y0111749*
Y0111803*
Y0111857*
Y0111911*
Y0111965*
Y0112019*
Y0112073*
Y0112127*
Y0112181*
Y0112235*
Y0112289*
Y0112343*
Y0112397*
Y0112452*
Y0112505*
Y011256*
Y0112614*
Y0112668*
Y0112722*
Y0112776*
Y011283*
Y0112884*
Y0112938*
Y0112992*
Y0113046*
Y01131*
Y0113154*
Y0113208*
Y0113262*
Y0113317*
Y0113371*
Y0113425*
Y0113479*
Y0113533*
Y0113587*
Y0113641*
Y0113695*
Y0113749*
Y0113803*
Y0113857*
Y0113911*
Y0113965*
Y0114019*
Y0114073*
Y0114127*
Y0114181*
Y0114235*
Y011429*
Y0114344*
Y0114398*
Y0114452*
X0590584*
Y0114506*
Y011456*
Y0114614*
Y0114668*
Y0114722*
X059053*
Y0114776*
Y011483*
X0590476*
Y0114884*
Y0114938*
X0590422*
Y0114992*
Y0115047*
X0590368*
Y0115101*
X0590314*
Y0115155*
Y0115209*
X059026*
Y0115263*
X0590205*
Y0115317*
X0590151*
Y0115371*
X0590043*
Y0115425*
X0589989*
Y0115479*
X0589881*
Y0115533*
X0589773*
Y0115587*
X0589665*
Y0115641*
X0589449*
Y0115695*
X0582583*
Y0115749*
Y0115803*
Y0115857*
Y0115911*
Y0115965*
Y011602*
Y0116074*
Y0116128*
Y0116182*
Y0116236*
Y011629*
Y0116344*
Y0116398*
Y0116452*
Y0116506*
Y011656*
Y0116614*
Y0116668*
Y0116722*
Y0116776*
Y0116831*
Y0116885*
Y0116939*
Y0116993*
Y0117047*
Y0117101*
Y0117155*
Y0117209*
Y0117263*
Y0117317*
Y0117371*
Y0117425*
Y0117479*
Y0117533*
Y0117587*
Y0117641*
Y0117695*
Y011775*
X0589449*
Y0117695*
G37*
%LNtimecard-dc-beta-v1-2*%
%LPC*%
G36*
X0639186Y0104558D02*
X0639023D01*
Y0104504*
X0638969*
Y0104558*
X0632644*
Y0104504*
X0632374*
Y010445*
X0632212*
Y0104396*
X0632103*
Y0104342*
X0632049*
Y0104288*
X0631995*
Y0104234*
X0631941*
Y010418*
X0631887*
Y0104126*
X0631833*
Y0104072*
X0631779*
Y0104018*
X0631725*
Y0103964*
X0631671*
Y010391*
X0631617*
Y0103856*
X0631563*
Y0103802*
X0631509*
Y0103747*
X0631455*
Y0103693*
X0631401*
Y0103639*
X0631347*
Y0103585*
X0631293*
Y0103531*
X0631239*
Y0103477*
X0631184*
Y0103423*
X063113*
Y0103369*
X0631076*
Y0103315*
X0631022*
Y0103261*
X0630968*
Y0103207*
X0630914*
Y0103153*
X063086*
Y0103099*
X0630806*
Y0103045*
X0630752*
Y0102991*
X0630698*
Y0102937*
X0630644*
Y0102883*
X063059*
Y0102828*
X0630536*
Y0102774*
Y010272*
Y0102666*
X0630482*
Y0102612*
Y0102558*
Y0102504*
Y010245*
Y0102396*
X0630428*
Y0102342*
Y0102288*
Y0102234*
Y010218*
Y0102126*
Y0102072*
Y0102017*
Y0101963*
Y0101909*
Y0101855*
Y0101801*
Y0101747*
Y0101693*
Y0101639*
Y0101585*
Y0101531*
Y0101477*
Y0101423*
Y0101369*
Y0101315*
Y0101261*
Y0101207*
Y0101153*
Y0101099*
Y0101044*
Y010099*
Y0100936*
Y0100882*
Y0100828*
Y0100774*
Y010072*
Y0100666*
Y0100612*
Y0100558*
Y0100504*
Y010045*
Y0100396*
Y0100342*
Y0100287*
Y0100233*
Y0100179*
Y0100125*
Y0100071*
Y0100017*
Y0099963*
Y0099909*
Y0099855*
Y0099801*
Y0099747*
Y0099693*
Y0099639*
Y0099585*
Y0099531*
Y0099477*
Y0099423*
Y0099369*
Y0099314*
Y009926*
Y0099206*
Y0099152*
Y0099098*
Y0099044*
Y009899*
Y0098936*
Y0098882*
Y0098828*
Y0098774*
Y009872*
Y0098666*
Y0098612*
Y0098558*
Y0098504*
Y0098449*
Y0098395*
Y0098341*
Y0098287*
Y0098233*
Y0098179*
Y0098125*
Y0098071*
Y0098017*
Y0097963*
Y0097909*
Y0097855*
Y0097801*
Y0097747*
Y0097693*
Y0097638*
Y0097584*
Y009753*
Y0097476*
Y0097422*
Y0097368*
Y0097314*
Y009726*
Y0097206*
Y0097152*
Y0097098*
Y0097044*
Y009699*
Y0096936*
Y0096882*
Y0096828*
Y0096773*
Y0096719*
Y0096665*
Y0096611*
Y0096557*
Y0096503*
Y0096449*
Y0096395*
Y0096341*
Y0096287*
Y0096233*
Y0096179*
Y0096125*
Y0096071*
Y0096017*
Y0095963*
Y0095908*
Y0095854*
Y00958*
Y0095746*
Y0095692*
Y0095638*
Y0095584*
Y009553*
Y0095476*
Y0095422*
Y0095368*
Y0095314*
Y009526*
Y0095206*
Y0095152*
Y0095098*
Y0095043*
Y009499*
Y0094935*
Y0094881*
X0630482*
Y0094827*
Y0094773*
Y0094719*
Y0094665*
Y0094611*
X0630536*
Y0094557*
Y0094503*
X063059*
Y0094449*
Y0094395*
X0630644*
Y0094341*
X0630698*
Y0094287*
X0630752*
Y0094233*
X0630806*
Y0094178*
X063086*
Y0094125*
X0630914*
Y009407*
X0630968*
Y0094016*
X0631022*
Y0093962*
X0631076*
Y0093908*
X063113*
Y0093854*
X0631184*
Y00938*
X0631239*
Y0093746*
X0631293*
Y0093692*
X0631347*
Y0093638*
X0631401*
Y0093584*
X0631455*
Y009353*
X0631509*
Y0093476*
X0631563*
Y0093422*
X0631617*
Y0093368*
X0631671*
Y0093313*
X0631725*
Y009326*
X0631779*
Y0093205*
X0631833*
Y0093151*
X0631887*
Y0093097*
X0631941*
Y0093043*
X0631995*
Y0092989*
X0632049*
Y0092935*
X0632103*
Y0092881*
X0632212*
Y0092827*
X0632428*
Y0092773*
X0639294*
Y0092827*
X0639348*
Y0092881*
X0639402*
Y0092935*
Y0092989*
X0639456*
Y0093043*
Y0093097*
Y0093151*
Y0093205*
Y009326*
Y0093313*
Y0093368*
Y0093422*
Y0093476*
Y009353*
Y0093584*
Y0093638*
Y0093692*
Y0093746*
Y00938*
Y0093854*
Y0093908*
Y0093962*
Y0094016*
Y009407*
Y0094125*
Y0094178*
Y0094233*
Y0094287*
Y0094341*
Y0094395*
Y0094449*
Y0094503*
Y0094557*
Y0094611*
Y0094665*
Y0094719*
Y0094773*
Y0094827*
Y0094881*
Y0094935*
Y009499*
Y0095043*
Y0095098*
Y0095152*
Y0095206*
Y009526*
Y0095314*
X0639402*
Y0095368*
Y0095422*
X0639348*
Y0095476*
X063924*
Y009553*
X0633455*
Y0095584*
X0633401*
Y0095638*
Y0095692*
Y0095746*
Y00958*
Y0095854*
Y0095908*
Y0095963*
Y0096017*
Y0096071*
Y0096125*
Y0096179*
Y0096233*
Y0096287*
Y0096341*
Y0096395*
Y0096449*
Y0096503*
Y0096557*
Y0096611*
Y0096665*
Y0096719*
Y0096773*
Y0096828*
Y0096882*
Y0096936*
Y009699*
Y0097044*
Y0097098*
Y0097152*
Y0097206*
Y009726*
Y0097314*
Y0097368*
Y0097422*
X0633455*
Y0097476*
X0638429*
Y009753*
X0638537*
Y0097584*
Y0097638*
X0638591*
Y0097693*
Y0097747*
Y0097801*
Y0097855*
Y0097909*
Y0097963*
Y0098017*
Y0098071*
Y0098125*
Y0098179*
Y0098233*
Y0098287*
Y0098341*
Y0098395*
Y0098449*
Y0098504*
Y0098558*
Y0098612*
Y0098666*
Y009872*
Y0098774*
Y0098828*
Y0098882*
Y0098936*
Y009899*
Y0099044*
Y0099098*
Y0099152*
Y0099206*
Y009926*
Y0099314*
Y0099369*
Y0099423*
Y0099477*
Y0099531*
Y0099585*
Y0099639*
X0638537*
Y0099693*
Y0099747*
X0638429*
Y0099801*
X0633455*
Y0099855*
X0633401*
Y0099909*
Y0099963*
Y0100017*
Y0100071*
Y0100125*
Y0100179*
Y0100233*
Y0100287*
Y0100342*
Y0100396*
Y010045*
Y0100504*
Y0100558*
Y0100612*
Y0100666*
Y010072*
Y0100774*
Y0100828*
Y0100882*
Y0100936*
Y010099*
Y0101044*
Y0101099*
Y0101153*
Y0101207*
Y0101261*
Y0101315*
Y0101369*
Y0101423*
Y0101477*
Y0101531*
Y0101585*
Y0101639*
Y0101693*
Y0101747*
X0633455*
Y0101801*
X0639294*
Y0101855*
X0639348*
Y0101909*
X0639402*
Y0101963*
X0639456*
Y0102017*
Y0102072*
Y0102126*
Y010218*
Y0102234*
Y0102288*
Y0102342*
Y0102396*
Y010245*
Y0102504*
Y0102558*
Y0102612*
Y0102666*
Y010272*
Y0102774*
Y0102828*
Y0102883*
Y0102937*
Y0102991*
Y0103045*
Y0103099*
Y0103153*
Y0103207*
Y0103261*
Y0103315*
Y0103369*
Y0103423*
Y0103477*
Y0103531*
Y0103585*
Y0103639*
Y0103693*
Y0103747*
Y0103802*
Y0103856*
Y010391*
Y0103964*
Y0104018*
Y0104072*
Y0104126*
Y010418*
Y0104234*
Y0104288*
X0639402*
Y0104342*
Y0104396*
X0639348*
Y010445*
X0639294*
Y0104504*
X0639186*
Y0104558*
G37*
G36*
X0611506D02*
X0611398D01*
Y0104504*
X0611344*
Y0104558*
X0603018*
Y0104504*
X0602856*
Y010445*
X0602802*
Y0104396*
Y0104342*
X0602748*
Y0104288*
Y0104234*
Y010418*
Y0104126*
Y0104072*
Y0104018*
Y0103964*
Y010391*
Y0103856*
Y0103802*
Y0103747*
Y0103693*
Y0103639*
Y0103585*
Y0103531*
Y0103477*
Y0103423*
Y0103369*
Y0103315*
Y0103261*
Y0103207*
Y0103153*
Y0103099*
Y0103045*
Y0102991*
Y0102937*
Y0102883*
Y0102828*
Y0102774*
Y010272*
Y0102666*
Y0102612*
Y0102558*
Y0102504*
Y010245*
Y0102396*
Y0102342*
Y0102288*
Y0102234*
Y010218*
Y0102126*
Y0102072*
Y0102017*
Y0101963*
Y0101909*
Y0101855*
X0602802*
Y0101801*
X0602856*
Y0101747*
X060291*
Y0101693*
X0603018*
Y0101639*
X0605613*
Y0101585*
X0605667*
Y0101531*
X0605721*
Y0101477*
Y0101423*
X0605775*
Y0101369*
Y0101315*
Y0101261*
Y0101207*
Y0101153*
Y0101099*
Y0101044*
Y010099*
Y0100936*
Y0100882*
Y0100828*
Y0100774*
Y010072*
Y0100666*
Y0100612*
Y0100558*
Y0100504*
Y010045*
Y0100396*
Y0100342*
Y0100287*
Y0100233*
Y0100179*
Y0100125*
Y0100071*
Y0100017*
Y0099963*
Y0099909*
Y0099855*
Y0099801*
Y0099747*
Y0099693*
Y0099639*
Y0099585*
Y0099531*
Y0099477*
Y0099423*
Y0099369*
Y0099314*
Y009926*
Y0099206*
Y0099152*
Y0099098*
Y0099044*
Y009899*
Y0098936*
Y0098882*
Y0098828*
Y0098774*
Y009872*
Y0098666*
Y0098612*
Y0098558*
Y0098504*
Y0098449*
Y0098395*
Y0098341*
Y0098287*
Y0098233*
Y0098179*
Y0098125*
Y0098071*
Y0098017*
Y0097963*
Y0097909*
Y0097855*
Y0097801*
Y0097747*
Y0097693*
Y0097638*
Y0097584*
Y009753*
Y0097476*
Y0097422*
Y0097368*
Y0097314*
Y009726*
Y0097206*
Y0097152*
Y0097098*
Y0097044*
Y009699*
Y0096936*
Y0096882*
Y0096828*
Y0096773*
Y0096719*
Y0096665*
Y0096611*
Y0096557*
Y0096503*
Y0096449*
Y0096395*
Y0096341*
Y0096287*
Y0096233*
Y0096179*
Y0096125*
Y0096071*
Y0096017*
Y0095963*
Y0095908*
Y0095854*
Y00958*
Y0095746*
Y0095692*
Y0095638*
Y0095584*
Y009553*
Y0095476*
Y0095422*
Y0095368*
Y0095314*
Y009526*
Y0095206*
Y0095152*
Y0095098*
Y0095043*
Y009499*
Y0094935*
Y0094881*
Y0094827*
Y0094773*
Y0094719*
Y0094665*
Y0094611*
Y0094557*
Y0094503*
Y0094449*
Y0094395*
Y0094341*
Y0094287*
Y0094233*
Y0094178*
Y0094125*
Y009407*
Y0094016*
Y0093962*
Y0093908*
Y0093854*
Y00938*
Y0093746*
Y0093692*
Y0093638*
Y0093584*
Y009353*
Y0093476*
Y0093422*
Y0093368*
Y0093313*
Y009326*
Y0093205*
Y0093151*
Y0093097*
Y0093043*
Y0092989*
Y0092935*
X0605829*
Y0092881*
X0605883*
Y0092827*
X0605937*
Y0092773*
X0608587*
Y0092827*
X0608641*
Y0092881*
X0608695*
Y0092935*
Y0092989*
Y0093043*
X0608749*
Y0093097*
Y0093151*
Y0093205*
Y009326*
Y0093313*
Y0093368*
Y0093422*
Y0093476*
Y009353*
Y0093584*
Y0093638*
Y0093692*
Y0093746*
Y00938*
Y0093854*
Y0093908*
Y0093962*
Y0094016*
Y009407*
Y0094125*
Y0094178*
Y0094233*
Y0094287*
Y0094341*
Y0094395*
Y0094449*
Y0094503*
Y0094557*
Y0094611*
Y0094665*
Y0094719*
Y0094773*
Y0094827*
Y0094881*
Y0094935*
Y009499*
Y0095043*
Y0095098*
Y0095152*
Y0095206*
Y009526*
Y0095314*
Y0095368*
Y0095422*
Y0095476*
Y009553*
Y0095584*
Y0095638*
Y0095692*
Y0095746*
Y00958*
Y0095854*
Y0095908*
Y0095963*
Y0096017*
Y0096071*
Y0096125*
Y0096179*
Y0096233*
Y0096287*
Y0096341*
Y0096395*
Y0096449*
Y0096503*
Y0096557*
Y0096611*
Y0096665*
Y0096719*
Y0096773*
Y0096828*
Y0096882*
Y0096936*
Y009699*
Y0097044*
Y0097098*
Y0097152*
Y0097206*
Y009726*
Y0097314*
Y0097368*
Y0097422*
Y0097476*
Y009753*
Y0097584*
Y0097638*
Y0097693*
Y0097747*
Y0097801*
Y0097855*
Y0097909*
Y0097963*
Y0098017*
Y0098071*
Y0098125*
Y0098179*
Y0098233*
Y0098287*
Y0098341*
Y0098395*
Y0098449*
Y0098504*
Y0098558*
Y0098612*
Y0098666*
Y009872*
Y0098774*
Y0098828*
Y0098882*
Y0098936*
Y009899*
Y0099044*
Y0099098*
Y0099152*
Y0099206*
Y009926*
Y0099314*
Y0099369*
Y0099423*
Y0099477*
Y0099531*
Y0099585*
Y0099639*
Y0099693*
Y0099747*
Y0099801*
Y0099855*
Y0099909*
Y0099963*
Y0100017*
Y0100071*
Y0100125*
Y0100179*
Y0100233*
Y0100287*
Y0100342*
Y0100396*
Y010045*
Y0100504*
Y0100558*
Y0100612*
Y0100666*
Y010072*
Y0100774*
Y0100828*
Y0100882*
Y0100936*
Y010099*
Y0101044*
Y0101099*
Y0101153*
Y0101207*
Y0101261*
Y0101315*
Y0101369*
Y0101423*
Y0101477*
Y0101531*
X0608803*
Y0101585*
X0608857*
Y0101639*
X0611452*
Y0101693*
X0611614*
Y0101747*
X0611668*
Y0101801*
X0611722*
Y0101855*
Y0101909*
Y0101963*
X0611776*
Y0102017*
Y0102072*
Y0102126*
Y010218*
Y0102234*
Y0102288*
Y0102342*
Y0102396*
Y010245*
Y0102504*
Y0102558*
Y0102612*
Y0102666*
Y010272*
Y0102774*
Y0102828*
Y0102883*
Y0102937*
Y0102991*
Y0103045*
Y0103099*
Y0103153*
Y0103207*
Y0103261*
Y0103315*
Y0103369*
Y0103423*
Y0103477*
Y0103531*
Y0103585*
Y0103639*
Y0103693*
Y0103747*
Y0103802*
Y0103856*
Y010391*
Y0103964*
Y0104018*
Y0104072*
Y0104126*
Y010418*
Y0104234*
X0611722*
Y0104288*
Y0104342*
Y0104396*
X0611668*
Y010445*
X0611614*
Y0104504*
X0611506*
Y0104558*
G37*
G36*
X0625292D02*
X061702D01*
Y0104504*
X0616858*
Y010445*
X0616804*
Y0104396*
Y0104342*
X061675*
Y0104288*
Y0104234*
Y010418*
Y0104126*
Y0104072*
Y0104018*
Y0103964*
Y010391*
Y0103856*
Y0103802*
Y0103747*
Y0103693*
Y0103639*
Y0103585*
Y0103531*
Y0103477*
Y0103423*
Y0103369*
Y0103315*
Y0103261*
Y0103207*
Y0103153*
Y0103099*
Y0103045*
Y0102991*
Y0102937*
Y0102883*
Y0102828*
Y0102774*
Y010272*
Y0102666*
Y0102612*
Y0102558*
Y0102504*
Y010245*
Y0102396*
Y0102342*
Y0102288*
Y0102234*
Y010218*
Y0102126*
Y0102072*
Y0102017*
Y0101963*
Y0101909*
Y0101855*
Y0101801*
Y0101747*
Y0101693*
Y0101639*
Y0101585*
Y0101531*
Y0101477*
Y0101423*
Y0101369*
Y0101315*
Y0101261*
Y0101207*
Y0101153*
Y0101099*
Y0101044*
Y010099*
Y0100936*
Y0100882*
Y0100828*
Y0100774*
Y010072*
Y0100666*
Y0100612*
Y0100558*
Y0100504*
Y010045*
Y0100396*
Y0100342*
Y0100287*
Y0100233*
Y0100179*
Y0100125*
Y0100071*
Y0100017*
Y0099963*
Y0099909*
Y0099855*
Y0099801*
Y0099747*
Y0099693*
Y0099639*
Y0099585*
Y0099531*
Y0099477*
Y0099423*
Y0099369*
Y0099314*
Y009926*
Y0099206*
Y0099152*
Y0099098*
Y0099044*
Y009899*
Y0098936*
Y0098882*
Y0098828*
Y0098774*
Y009872*
Y0098666*
Y0098612*
Y0098558*
Y0098504*
Y0098449*
Y0098395*
Y0098341*
Y0098287*
Y0098233*
Y0098179*
Y0098125*
Y0098071*
Y0098017*
Y0097963*
Y0097909*
Y0097855*
Y0097801*
Y0097747*
Y0097693*
Y0097638*
Y0097584*
Y009753*
Y0097476*
Y0097422*
Y0097368*
Y0097314*
Y009726*
Y0097206*
Y0097152*
Y0097098*
Y0097044*
Y009699*
Y0096936*
Y0096882*
Y0096828*
Y0096773*
Y0096719*
Y0096665*
Y0096611*
Y0096557*
Y0096503*
Y0096449*
Y0096395*
Y0096341*
Y0096287*
Y0096233*
Y0096179*
Y0096125*
Y0096071*
Y0096017*
Y0095963*
Y0095908*
Y0095854*
Y00958*
Y0095746*
Y0095692*
Y0095638*
Y0095584*
Y009553*
Y0095476*
Y0095422*
Y0095368*
Y0095314*
Y009526*
Y0095206*
Y0095152*
Y0095098*
Y0095043*
Y009499*
Y0094935*
Y0094881*
Y0094827*
Y0094773*
Y0094719*
Y0094665*
Y0094611*
Y0094557*
Y0094503*
Y0094449*
Y0094395*
Y0094341*
Y0094287*
Y0094233*
Y0094178*
Y0094125*
Y009407*
Y0094016*
Y0093962*
Y0093908*
Y0093854*
Y00938*
Y0093746*
Y0093692*
Y0093638*
Y0093584*
Y009353*
Y0093476*
Y0093422*
Y0093368*
Y0093313*
Y009326*
Y0093205*
Y0093151*
Y0093097*
Y0093043*
Y0092989*
Y0092935*
X0616804*
Y0092881*
Y0092827*
X0616912*
Y0092773*
X0619561*
Y0092827*
X0619615*
Y0092881*
X0619669*
Y0092935*
Y0092989*
X0619723*
Y0093043*
Y0093097*
Y0093151*
Y0093205*
Y009326*
Y0093313*
Y0093368*
Y0093422*
Y0093476*
Y009353*
Y0093584*
Y0093638*
Y0093692*
Y0093746*
Y00938*
Y0093854*
Y0093908*
Y0093962*
Y0094016*
Y009407*
Y0094125*
Y0094178*
Y0094233*
Y0094287*
Y0094341*
Y0094395*
Y0094449*
Y0094503*
Y0094557*
Y0094611*
Y0094665*
Y0094719*
Y0094773*
Y0094827*
Y0094881*
Y0094935*
Y009499*
Y0095043*
Y0095098*
Y0095152*
Y0095206*
Y009526*
Y0095314*
Y0095368*
Y0095422*
Y0095476*
Y009553*
Y0095584*
Y0095638*
Y0095692*
Y0095746*
Y00958*
Y0095854*
Y0095908*
Y0095963*
Y0096017*
Y0096071*
Y0096125*
Y0096179*
Y0096233*
Y0096287*
Y0096341*
Y0096395*
Y0096449*
Y0096503*
Y0096557*
Y0096611*
Y0096665*
Y0096719*
Y0096773*
Y0096828*
Y0096882*
Y0096936*
Y009699*
Y0097044*
Y0097098*
Y0097152*
Y0097206*
Y009726*
Y0097314*
Y0097368*
Y0097422*
Y0097476*
Y009753*
Y0097584*
Y0097638*
Y0097693*
Y0097747*
Y0097801*
Y0097855*
Y0097909*
Y0097963*
Y0098017*
Y0098071*
Y0098125*
Y0098179*
Y0098233*
Y0098287*
Y0098341*
Y0098395*
Y0098449*
Y0098504*
Y0098558*
Y0098612*
Y0098666*
Y009872*
Y0098774*
Y0098828*
Y0098882*
Y0098936*
Y009899*
Y0099044*
Y0099098*
Y0099152*
Y0099206*
Y009926*
Y0099314*
Y0099369*
Y0099423*
Y0099477*
Y0099531*
Y0099585*
Y0099639*
Y0099693*
Y0099747*
Y0099801*
Y0099855*
Y0099909*
Y0099963*
Y0100017*
Y0100071*
Y0100125*
Y0100179*
Y0100233*
Y0100287*
Y0100342*
Y0100396*
Y010045*
Y0100504*
Y0100558*
Y0100612*
Y0100666*
Y010072*
Y0100774*
Y0100828*
Y0100882*
Y0100936*
Y010099*
Y0101044*
Y0101099*
Y0101153*
Y0101207*
Y0101261*
Y0101315*
Y0101369*
Y0101423*
Y0101477*
Y0101531*
Y0101585*
Y0101639*
X0621561*
Y0101585*
Y0101531*
Y0101477*
Y0101423*
Y0101369*
Y0101315*
Y0101261*
Y0101207*
Y0101153*
Y0101099*
Y0101044*
Y010099*
Y0100936*
Y0100882*
Y0100828*
Y0100774*
Y010072*
Y0100666*
Y0100612*
Y0100558*
Y0100504*
Y010045*
Y0100396*
Y0100342*
Y0100287*
Y0100233*
Y0100179*
Y0100125*
Y0100071*
Y0100017*
Y0099963*
Y0099909*
Y0099855*
Y0099801*
Y0099747*
Y0099693*
Y0099639*
Y0099585*
Y0099531*
Y0099477*
Y0099423*
Y0099369*
Y0099314*
Y009926*
Y0099206*
Y0099152*
Y0099098*
Y0099044*
Y009899*
Y0098936*
Y0098882*
Y0098828*
Y0098774*
Y009872*
Y0098666*
Y0098612*
Y0098558*
Y0098504*
Y0098449*
Y0098395*
Y0098341*
Y0098287*
Y0098233*
Y0098179*
Y0098125*
Y0098071*
Y0098017*
Y0097963*
Y0097909*
Y0097855*
Y0097801*
Y0097747*
Y0097693*
Y0097638*
Y0097584*
Y009753*
Y0097476*
Y0097422*
Y0097368*
Y0097314*
Y009726*
Y0097206*
Y0097152*
Y0097098*
Y0097044*
Y009699*
Y0096936*
Y0096882*
Y0096828*
Y0096773*
Y0096719*
Y0096665*
Y0096611*
Y0096557*
Y0096503*
Y0096449*
Y0096395*
Y0096341*
Y0096287*
Y0096233*
Y0096179*
Y0096125*
Y0096071*
Y0096017*
Y0095963*
Y0095908*
Y0095854*
Y00958*
Y0095746*
Y0095692*
Y0095638*
Y0095584*
Y009553*
Y0095476*
Y0095422*
Y0095368*
Y0095314*
Y009526*
Y0095206*
Y0095152*
Y0095098*
Y0095043*
Y009499*
Y0094935*
Y0094881*
Y0094827*
Y0094773*
Y0094719*
Y0094665*
Y0094611*
Y0094557*
Y0094503*
Y0094449*
Y0094395*
Y0094341*
Y0094287*
Y0094233*
Y0094178*
Y0094125*
Y009407*
Y0094016*
Y0093962*
Y0093908*
Y0093854*
Y00938*
Y0093746*
Y0093692*
Y0093638*
Y0093584*
Y009353*
Y0093476*
Y0093422*
Y0093368*
Y0093313*
Y009326*
Y0093205*
Y0093151*
Y0093097*
Y0093043*
Y0092989*
X0621615*
Y0092935*
Y0092881*
X0621669*
Y0092827*
X0621778*
Y0092773*
X0624156*
Y0092827*
X062421*
Y0092881*
X0624264*
Y0092935*
X0624319*
Y0092989*
Y0093043*
Y0093097*
Y0093151*
Y0093205*
Y009326*
Y0093313*
Y0093368*
Y0093422*
Y0093476*
Y009353*
Y0093584*
Y0093638*
Y0093692*
Y0093746*
Y00938*
Y0093854*
Y0093908*
Y0093962*
Y0094016*
Y009407*
Y0094125*
Y0094178*
Y0094233*
Y0094287*
Y0094341*
Y0094395*
Y0094449*
Y0094503*
Y0094557*
Y0094611*
Y0094665*
Y0094719*
Y0094773*
Y0094827*
Y0094881*
Y0094935*
Y009499*
Y0095043*
Y0095098*
Y0095152*
Y0095206*
Y009526*
Y0095314*
Y0095368*
Y0095422*
Y0095476*
Y009553*
Y0095584*
Y0095638*
Y0095692*
Y0095746*
Y00958*
Y0095854*
Y0095908*
Y0095963*
Y0096017*
Y0096071*
Y0096125*
Y0096179*
Y0096233*
Y0096287*
Y0096341*
Y0096395*
Y0096449*
Y0096503*
Y0096557*
Y0096611*
Y0096665*
Y0096719*
Y0096773*
Y0096828*
Y0096882*
Y0096936*
Y009699*
Y0097044*
Y0097098*
Y0097152*
Y0097206*
Y009726*
Y0097314*
Y0097368*
Y0097422*
Y0097476*
Y009753*
Y0097584*
Y0097638*
Y0097693*
Y0097747*
Y0097801*
Y0097855*
Y0097909*
Y0097963*
Y0098017*
Y0098071*
Y0098125*
Y0098179*
Y0098233*
Y0098287*
Y0098341*
Y0098395*
Y0098449*
Y0098504*
Y0098558*
Y0098612*
Y0098666*
Y009872*
Y0098774*
Y0098828*
Y0098882*
Y0098936*
Y009899*
Y0099044*
Y0099098*
Y0099152*
Y0099206*
Y009926*
Y0099314*
Y0099369*
Y0099423*
Y0099477*
Y0099531*
Y0099585*
Y0099639*
Y0099693*
Y0099747*
Y0099801*
Y0099855*
Y0099909*
Y0099963*
Y0100017*
Y0100071*
Y0100125*
Y0100179*
Y0100233*
Y0100287*
Y0100342*
Y0100396*
Y010045*
Y0100504*
Y0100558*
Y0100612*
Y0100666*
Y010072*
Y0100774*
Y0100828*
Y0100882*
Y0100936*
Y010099*
Y0101044*
Y0101099*
Y0101153*
Y0101207*
Y0101261*
Y0101315*
Y0101369*
Y0101423*
Y0101477*
Y0101531*
Y0101585*
Y0101639*
X0625075*
Y0101693*
X062513*
Y0101639*
X0625292*
Y0101693*
Y0101747*
Y0101801*
Y0101855*
Y0101909*
Y0101963*
Y0102017*
Y0102072*
Y0102126*
Y010218*
Y0102234*
Y0102288*
Y0102342*
Y0102396*
Y010245*
Y0102504*
Y0102558*
Y0102612*
Y0102666*
Y010272*
Y0102774*
Y0102828*
Y0102883*
Y0102937*
Y0102991*
Y0103045*
Y0103099*
Y0103153*
Y0103207*
Y0103261*
Y0103315*
Y0103369*
Y0103423*
Y0103477*
Y0103531*
Y0103585*
Y0103639*
Y0103693*
Y0103747*
Y0103802*
Y0103856*
Y010391*
Y0103964*
Y0104018*
Y0104072*
Y0104126*
Y010418*
Y0104234*
Y0104288*
Y0104342*
Y0104396*
Y010445*
Y0104504*
Y0104558*
G37*
G36*
X0615182D02*
X0612695D01*
Y0104504*
X0612533*
Y010445*
Y0104396*
X0612479*
Y0104342*
Y0104288*
X0612425*
Y0104234*
Y010418*
Y0104126*
Y0104072*
Y0104018*
Y0103964*
Y010391*
Y0103856*
Y0103802*
Y0103747*
Y0103693*
Y0103639*
Y0103585*
Y0103531*
Y0103477*
Y0103423*
Y0103369*
Y0103315*
Y0103261*
Y0103207*
Y0103153*
Y0103099*
Y0103045*
Y0102991*
Y0102937*
Y0102883*
Y0102828*
Y0102774*
Y010272*
Y0102666*
Y0102612*
Y0102558*
Y0102504*
Y010245*
Y0102396*
Y0102342*
Y0102288*
Y0102234*
Y010218*
Y0102126*
Y0102072*
Y0102017*
Y0101963*
Y0101909*
Y0101855*
Y0101801*
Y0101747*
Y0101693*
Y0101639*
Y0101585*
Y0101531*
Y0101477*
Y0101423*
Y0101369*
Y0101315*
Y0101261*
Y0101207*
Y0101153*
Y0101099*
Y0101044*
Y010099*
Y0100936*
Y0100882*
Y0100828*
Y0100774*
Y010072*
Y0100666*
Y0100612*
Y0100558*
Y0100504*
Y010045*
Y0100396*
Y0100342*
Y0100287*
Y0100233*
Y0100179*
Y0100125*
Y0100071*
Y0100017*
Y0099963*
Y0099909*
Y0099855*
Y0099801*
Y0099747*
Y0099693*
Y0099639*
Y0099585*
Y0099531*
Y0099477*
Y0099423*
Y0099369*
Y0099314*
Y009926*
Y0099206*
Y0099152*
Y0099098*
Y0099044*
Y009899*
Y0098936*
Y0098882*
Y0098828*
Y0098774*
Y009872*
Y0098666*
Y0098612*
Y0098558*
Y0098504*
Y0098449*
Y0098395*
Y0098341*
Y0098287*
Y0098233*
Y0098179*
Y0098125*
Y0098071*
Y0098017*
Y0097963*
Y0097909*
Y0097855*
Y0097801*
Y0097747*
Y0097693*
Y0097638*
Y0097584*
Y009753*
Y0097476*
Y0097422*
Y0097368*
Y0097314*
Y009726*
Y0097206*
Y0097152*
Y0097098*
Y0097044*
Y009699*
Y0096936*
Y0096882*
Y0096828*
Y0096773*
Y0096719*
Y0096665*
Y0096611*
Y0096557*
Y0096503*
Y0096449*
Y0096395*
Y0096341*
Y0096287*
Y0096233*
Y0096179*
Y0096125*
Y0096071*
Y0096017*
Y0095963*
Y0095908*
Y0095854*
Y00958*
Y0095746*
Y0095692*
Y0095638*
Y0095584*
Y009553*
Y0095476*
Y0095422*
Y0095368*
Y0095314*
Y009526*
Y0095206*
Y0095152*
Y0095098*
Y0095043*
Y009499*
Y0094935*
Y0094881*
Y0094827*
Y0094773*
Y0094719*
Y0094665*
Y0094611*
Y0094557*
Y0094503*
Y0094449*
Y0094395*
Y0094341*
Y0094287*
Y0094233*
Y0094178*
Y0094125*
Y009407*
Y0094016*
Y0093962*
Y0093908*
Y0093854*
Y00938*
Y0093746*
Y0093692*
Y0093638*
Y0093584*
Y009353*
Y0093476*
Y0093422*
Y0093368*
Y0093313*
Y009326*
Y0093205*
Y0093151*
Y0093097*
Y0093043*
Y0092989*
X0612479*
Y0092935*
Y0092881*
X0612533*
Y0092827*
X0612587*
Y0092773*
X061529*
Y0092827*
X0615344*
Y0092881*
X0615398*
Y0092935*
Y0092989*
Y0093043*
Y0093097*
Y0093151*
Y0093205*
Y009326*
Y0093313*
Y0093368*
Y0093422*
Y0093476*
Y009353*
Y0093584*
Y0093638*
Y0093692*
Y0093746*
Y00938*
Y0093854*
Y0093908*
Y0093962*
Y0094016*
Y009407*
Y0094125*
Y0094178*
Y0094233*
Y0094287*
Y0094341*
Y0094395*
Y0094449*
Y0094503*
Y0094557*
Y0094611*
Y0094665*
Y0094719*
Y0094773*
Y0094827*
Y0094881*
Y0094935*
Y009499*
Y0095043*
Y0095098*
Y0095152*
Y0095206*
Y009526*
Y0095314*
Y0095368*
Y0095422*
Y0095476*
Y009553*
Y0095584*
Y0095638*
Y0095692*
Y0095746*
Y00958*
Y0095854*
Y0095908*
Y0095963*
Y0096017*
Y0096071*
Y0096125*
Y0096179*
Y0096233*
Y0096287*
Y0096341*
Y0096395*
Y0096449*
Y0096503*
Y0096557*
Y0096611*
Y0096665*
Y0096719*
Y0096773*
Y0096828*
Y0096882*
Y0096936*
Y009699*
Y0097044*
Y0097098*
Y0097152*
Y0097206*
Y009726*
Y0097314*
Y0097368*
Y0097422*
Y0097476*
Y009753*
Y0097584*
Y0097638*
Y0097693*
Y0097747*
Y0097801*
Y0097855*
Y0097909*
Y0097963*
Y0098017*
Y0098071*
Y0098125*
Y0098179*
Y0098233*
Y0098287*
Y0098341*
Y0098395*
Y0098449*
Y0098504*
Y0098558*
Y0098612*
Y0098666*
Y009872*
Y0098774*
Y0098828*
Y0098882*
Y0098936*
Y009899*
Y0099044*
Y0099098*
Y0099152*
Y0099206*
Y009926*
Y0099314*
Y0099369*
Y0099423*
Y0099477*
Y0099531*
Y0099585*
Y0099639*
Y0099693*
Y0099747*
Y0099801*
Y0099855*
Y0099909*
Y0099963*
Y0100017*
Y0100071*
Y0100125*
Y0100179*
Y0100233*
Y0100287*
Y0100342*
Y0100396*
Y010045*
Y0100504*
Y0100558*
Y0100612*
Y0100666*
Y010072*
Y0100774*
Y0100828*
Y0100882*
Y0100936*
Y010099*
Y0101044*
Y0101099*
Y0101153*
Y0101207*
Y0101261*
Y0101315*
Y0101369*
Y0101423*
Y0101477*
Y0101531*
Y0101585*
Y0101639*
Y0101693*
Y0101747*
Y0101801*
Y0101855*
Y0101909*
Y0101963*
Y0102017*
Y0102072*
Y0102126*
Y010218*
Y0102234*
Y0102288*
Y0102342*
Y0102396*
Y010245*
Y0102504*
Y0102558*
Y0102612*
Y0102666*
Y010272*
Y0102774*
Y0102828*
Y0102883*
Y0102937*
Y0102991*
Y0103045*
Y0103099*
Y0103153*
Y0103207*
Y0103261*
Y0103315*
Y0103369*
Y0103423*
Y0103477*
Y0103531*
Y0103585*
Y0103639*
Y0103693*
Y0103747*
Y0103802*
Y0103856*
Y010391*
Y0103964*
Y0104018*
Y0104072*
Y0104126*
Y010418*
Y0104234*
Y0104288*
Y0104342*
Y0104396*
X0615344*
Y010445*
X061529*
Y0104504*
X0615182*
Y0104558*
G37*
G36*
X0629022Y0113262D02*
X0627022D01*
Y0113208*
X0626211*
Y0113154*
X062567*
Y01131*
X0625238*
Y0113046*
X0624913*
Y0112992*
X0624535*
Y0112938*
X062421*
Y0112884*
X062394*
Y011283*
X062367*
Y0112776*
X0623399*
Y0112722*
X0623183*
Y0112668*
X0622967*
Y0112614*
X0622751*
Y011256*
X0622535*
Y0112505*
X0622372*
Y0112452*
X0622156*
Y0112397*
X0621994*
Y0112343*
X0621832*
Y0112289*
X0621615*
Y0112235*
X0621453*
Y0112181*
X0621291*
Y0112127*
X0621129*
Y0112073*
X0621021*
Y0112019*
X0620859*
Y0111965*
X0620696*
Y0111911*
X0620534*
Y0111857*
X0620426*
Y0111803*
X0620264*
Y0111749*
X0620156*
Y0111695*
X0619994*
Y0111641*
X0619885*
Y0111586*
X0619777*
Y0111532*
X0619615*
Y0111478*
X0619507*
Y0111424*
X0619399*
Y011137*
X0619291*
Y0111316*
X0619129*
Y0111262*
X0619021*
Y0111208*
X0618912*
Y0111154*
X0618804*
Y01111*
X0618696*
Y0111046*
X0618588*
Y0110992*
X061848*
Y0110938*
X0618372*
Y0110884*
X0618264*
Y011083*
X0618155*
Y0110776*
X0618101*
Y0110722*
X0617993*
Y0110668*
X0617885*
Y0110613*
X0617777*
Y0110559*
X0617669*
Y0110505*
X0617615*
Y0110451*
X0617507*
Y0110397*
X0617399*
Y0110343*
X0617345*
Y0110289*
X0617236*
Y0110235*
X0617128*
Y0110181*
X0617074*
Y0110127*
X0616966*
Y0110073*
X0616858*
Y0110019*
X0616804*
Y0109965*
X0616696*
Y0109911*
X0616642*
Y0109856*
X0616534*
Y0109802*
X061648*
Y0109748*
X0616371*
Y0109694*
X0616317*
Y010964*
X0616209*
Y0109586*
X0616155*
Y0109532*
X0616047*
Y0109478*
X0615993*
Y0109424*
X0615939*
Y010937*
X0615831*
Y0109316*
X0615777*
Y0109262*
X0615669*
Y0109208*
X0615615*
Y0109154*
X061556*
Y01091*
X0615452*
Y0109046*
X0615398*
Y0108992*
X0615344*
Y0108938*
X0615236*
Y0108883*
X0615182*
Y0108829*
X0615128*
Y0108775*
X0615074*
Y0108721*
X0614966*
Y0108667*
X0614912*
Y0108613*
X0614858*
Y0108559*
X0614804*
Y0108505*
X0614696*
Y0108451*
X0614641*
Y0108397*
X0614587*
Y0108343*
X0614533*
Y0108289*
X0614479*
Y0108235*
X0614371*
Y0108181*
X0614317*
Y0108126*
X0614263*
Y0108072*
X0614209*
Y0108018*
X0614155*
Y0107964*
X0614101*
Y010791*
X0614047*
Y0107856*
X0613993*
Y0107802*
X0613885*
Y0107748*
X0613831*
Y0107694*
X0613776*
Y010764*
X0613722*
Y0107586*
X0613668*
Y0107532*
X0613614*
Y0107478*
X061356*
Y0107424*
X0613506*
Y010737*
X0613452*
Y0107316*
X0613398*
Y0107262*
X0613344*
Y0107208*
X061329*
Y0107153*
X0613236*
Y0107099*
X0613182*
Y0107045*
X0613128*
Y0106991*
X0613074*
Y0106937*
X061302*
Y0106883*
X0612965*
Y0106829*
X0612912*
Y0106775*
X0612857*
Y0106721*
X0612803*
Y0106667*
X0612749*
Y0106613*
X0612695*
Y0106559*
X0612641*
Y0106505*
X0612587*
Y0106451*
Y0106397*
X0612533*
Y0106342*
X0612479*
Y0106288*
X0612425*
Y0106234*
X0612371*
Y010618*
X0612317*
Y0106126*
X0612263*
Y0106072*
X0612209*
Y0106018*
X0612155*
Y0105964*
Y010591*
X0612101*
Y0105856*
X0612046*
Y0105802*
X0611992*
Y0105748*
X0611938*
Y0105694*
X0611884*
Y010564*
Y0105586*
X061183*
Y0105532*
X0611776*
Y0105477*
X0611722*
Y0105423*
X0612587*
Y0105477*
X0612641*
Y0105532*
X0612695*
Y0105586*
Y010564*
X0612749*
Y0105694*
X0612803*
Y0105748*
X0612857*
Y0105802*
X0612912*
Y0105856*
X0612965*
Y010591*
X061302*
Y0105964*
X0613074*
Y0106018*
X0613128*
Y0106072*
Y0106126*
X0613182*
Y010618*
X0613236*
Y0106234*
X061329*
Y0106288*
X0613344*
Y0106342*
X0613398*
Y0106397*
X0613452*
Y0106451*
X0613506*
Y0106505*
X061356*
Y0106559*
X0613614*
Y0106613*
X0613668*
Y0106667*
X0613722*
Y0106721*
X0613776*
Y0106775*
X0613831*
Y0106829*
X0613885*
Y0106883*
X0613939*
Y0106937*
X0613993*
Y0106991*
X0614047*
Y0107045*
X0614101*
Y0107099*
X0614155*
Y0107153*
X0614209*
Y0107208*
X0614317*
Y0107262*
X0614371*
Y0107316*
X0614425*
Y010737*
X0614479*
Y0107424*
X0614533*
Y0107478*
X0614587*
Y0107532*
X0614641*
Y0107586*
X0614696*
Y010764*
X061475*
Y0107694*
X0614858*
Y0107748*
X0614912*
Y0107802*
X0614966*
Y0107856*
X061502*
Y010791*
X0615074*
Y0107964*
X0615182*
Y0108018*
X0615236*
Y0108072*
X061529*
Y0108126*
X0615344*
Y0108181*
X0615452*
Y0108235*
X0615507*
Y0108289*
X061556*
Y0108343*
X0615615*
Y0108397*
X0615723*
Y0108451*
X0615777*
Y0108505*
X0615831*
Y0108559*
X0615939*
Y0108613*
X0615993*
Y0108667*
X0616047*
Y0108721*
X0616155*
Y0108775*
X0616209*
Y0108829*
X0616263*
Y0108883*
X0616371*
Y0108938*
X0616426*
Y0108992*
X0616534*
Y0109046*
X0616588*
Y01091*
X0616696*
Y0109154*
X061675*
Y0109208*
X0616858*
Y0109262*
X0616912*
Y0109316*
X061702*
Y010937*
X0617074*
Y0109424*
X0617182*
Y0109478*
X0617236*
Y0109532*
X0617345*
Y0109586*
X0617453*
Y010964*
X0617507*
Y0109694*
X0617615*
Y0109748*
X0617723*
Y0109802*
X0617777*
Y0109856*
X0617885*
Y0109911*
X0617993*
Y0109965*
X0618047*
Y0110019*
X0618155*
Y0110073*
X0618264*
Y0110127*
X0618372*
Y0110181*
X061848*
Y0110235*
X0618588*
Y0110289*
X0618696*
Y0110343*
X061875*
Y0110397*
X0618858*
Y0110451*
X0618966*
Y0110505*
X0619074*
Y0110559*
X0619183*
Y0110613*
X0619345*
Y0110668*
X0619453*
Y0110722*
X0619561*
Y0110776*
X0619669*
Y011083*
X0619777*
Y0110884*
X0619885*
Y0110938*
X0620048*
Y0110992*
X0620156*
Y0111046*
X0620264*
Y01111*
X0620426*
Y0111154*
X0620534*
Y0111208*
X0620696*
Y0111262*
X0620859*
Y0111316*
X0620967*
Y011137*
X0621129*
Y0111424*
X0621291*
Y0111478*
X0621453*
Y0111532*
X0621561*
Y0111586*
X0621778*
Y0111641*
X062194*
Y0111695*
X0622102*
Y0111749*
X0622264*
Y0111803*
X062248*
Y0111857*
X0622643*
Y0111911*
X0622859*
Y0111965*
X0623075*
Y0112019*
X0623291*
Y0112073*
X0623508*
Y0112127*
X0623778*
Y0112181*
X0624048*
Y0112235*
X0624264*
Y0112289*
X0624643*
Y0112343*
X0624967*
Y0112397*
X0625346*
Y0112452*
X0625778*
Y0112505*
X0626373*
Y011256*
X0627346*
Y0112614*
X0628698*
Y011256*
X0628752*
Y0112614*
X0628806*
Y011256*
X0629671*
Y0112505*
X0630265*
Y0112452*
X0630752*
Y0112397*
X0631076*
Y0112343*
X0631401*
Y0112289*
X0631725*
Y0112235*
X0631995*
Y0112181*
X0632266*
Y0112127*
X0632536*
Y0112073*
X0632752*
Y0112019*
X0632969*
Y0111965*
X0633185*
Y0111911*
X0633401*
Y0111857*
X0633563*
Y0111803*
X0633779*
Y0111749*
X0633942*
Y0111695*
X0634104*
Y0111641*
X0634266*
Y0111586*
X0634428*
Y0111532*
X063459*
Y0111478*
X0634753*
Y0111424*
X0634915*
Y011137*
X0635077*
Y0111316*
X0635185*
Y0111262*
X0635347*
Y0111208*
X0635455*
Y0111154*
X0635617*
Y01111*
X0635726*
Y0111046*
X0635888*
Y0110992*
X0635996*
Y0110938*
X0636104*
Y0110884*
X0636266*
Y011083*
X0636374*
Y0110776*
X0636482*
Y0110722*
X0636591*
Y0110668*
X0636699*
Y0110613*
X0636861*
Y0110559*
X0636969*
Y0110505*
X0637023*
Y0110451*
X0637131*
Y0110397*
X0637239*
Y0110343*
X0637348*
Y0110289*
X0637456*
Y0110235*
X0637564*
Y0110181*
X0637672*
Y0110127*
X063778*
Y0110073*
X0637888*
Y0110019*
X0637942*
Y0109965*
X063805*
Y0109911*
X0638158*
Y0109856*
X0638267*
Y0109802*
X0638321*
Y0109748*
X0638429*
Y0109694*
X0638537*
Y010964*
X0638591*
Y0109586*
X0638699*
Y0109532*
X0638807*
Y0109478*
X0638861*
Y0109424*
X0638969*
Y010937*
X0639023*
Y0109316*
X0639131*
Y0109262*
X0639186*
Y0109208*
X0639294*
Y0109154*
X0639348*
Y01091*
X0639456*
Y0109046*
X063951*
Y0108992*
X0639618*
Y0108938*
X0639672*
Y0108883*
X0639726*
Y0108829*
X0639834*
Y0108775*
X0639888*
Y0108721*
X0639996*
Y0108667*
X0640051*
Y0108613*
X0640105*
Y0108559*
X0640213*
Y0108505*
X0640267*
Y0108451*
X0640321*
Y0108397*
X0640429*
Y0108343*
X0640483*
Y0108289*
X0640537*
Y0108235*
X0640591*
Y0108181*
X0640699*
Y0108126*
X0640753*
Y0108072*
X0640807*
Y0108018*
X0640862*
Y0107964*
X064097*
Y010791*
X0641024*
Y0107856*
X0641078*
Y0107802*
X0641132*
Y0107748*
X0641186*
Y0107694*
X064124*
Y010764*
X0641348*
Y0107586*
X0641402*
Y0107532*
X0641456*
Y0107478*
X064151*
Y0107424*
X0641564*
Y010737*
X0641618*
Y0107316*
X0641673*
Y0107262*
X0641726*
Y0107208*
X0641781*
Y0107153*
X0641889*
Y0107099*
X0641943*
Y0107045*
X0641997*
Y0106991*
X0642051*
Y0106937*
X0642105*
Y0106883*
X0642159*
Y0106829*
X0642213*
Y0106775*
X0642267*
Y0106721*
X0642321*
Y0106667*
X0642375*
Y0106613*
X0642429*
Y0106559*
X0642483*
Y0106505*
X0642537*
Y0106451*
X0642591*
Y0106397*
X0642646*
Y0106342*
X06427*
Y0106288*
X0642754*
Y0106234*
X0642808*
Y010618*
Y0106126*
X0642862*
Y0106072*
X0642916*
Y0106018*
X064297*
Y0105964*
X0643024*
Y010591*
X0643078*
Y0105856*
X0643132*
Y0105802*
X0643186*
Y0105748*
X064324*
Y0105694*
X0643294*
Y010564*
Y0105586*
X0643348*
Y0105532*
X0643402*
Y0105477*
X0643457*
Y0105423*
X0643511*
Y0105369*
X0643565*
Y0105315*
X0643619*
Y0105261*
Y0105207*
X0643673*
Y0105153*
X0643727*
Y0105099*
X0643781*
Y0105045*
X0643835*
Y0104991*
Y0104937*
X0643889*
Y0104883*
X0643943*
Y0104829*
X0643997*
Y0104775*
X0644051*
Y0104721*
Y0104667*
X0644105*
Y0104613*
X0644159*
Y0104558*
X0644213*
Y0104504*
Y010445*
X0644267*
Y0104396*
X0644321*
Y0104342*
X0644376*
Y0104288*
Y0104234*
X064443*
Y010418*
X0644484*
Y0104126*
Y0104072*
X0644538*
Y0104018*
X0644592*
Y0103964*
X0644646*
Y010391*
Y0103856*
X06447*
Y0103802*
X0644754*
Y0103747*
Y0103693*
X0644808*
Y0103639*
X0644862*
Y0103585*
Y0103531*
X0644916*
Y0103477*
X064497*
Y0103423*
Y0103369*
X0645024*
Y0103315*
X0645078*
Y0103261*
Y0103207*
X0645132*
Y0103153*
X0645187*
Y0103099*
Y0103045*
X064524*
Y0102991*
Y0102937*
X0645295*
Y0102883*
X0645349*
Y0102828*
Y0102774*
X0645403*
Y010272*
Y0102666*
X0645457*
Y0102612*
X0645511*
Y0102558*
Y0102504*
X0645565*
Y010245*
Y0102396*
X0645619*
Y0102342*
Y0102288*
X0645673*
Y0102234*
X0645727*
Y010218*
Y0102126*
X0645781*
Y0102072*
Y0102017*
X0645835*
Y0101963*
Y0101909*
X0645889*
Y0101855*
Y0101801*
X0645943*
Y0101747*
Y0101693*
X0645997*
Y0101639*
X0646052*
Y0101585*
Y0101531*
X0646105*
Y0101477*
Y0101423*
X064616*
Y0101369*
Y0101315*
X0646214*
Y0101261*
Y0101207*
X0646268*
Y0101153*
Y0101099*
Y0101044*
X0646322*
Y010099*
Y0100936*
X0646376*
Y0100882*
Y0100828*
X064643*
Y0100774*
Y010072*
X0646484*
Y0100666*
Y0100612*
X0646538*
Y0100558*
Y0100504*
X0646592*
Y010045*
Y0100396*
Y0100342*
X0646646*
Y0100287*
Y0100233*
X06467*
Y0100179*
Y0100125*
X0646754*
Y0100071*
Y0100017*
Y0099963*
X0646808*
Y0099909*
Y0099855*
X0646862*
Y0099801*
Y0099747*
Y0099693*
X0646916*
Y0099639*
Y0099585*
X0646971*
Y0099531*
Y0099477*
Y0099423*
X0647025*
Y0099369*
Y0099314*
Y009926*
X0647079*
Y0099206*
Y0099152*
Y0099098*
X0647133*
Y0099044*
Y009899*
X0647187*
Y0098936*
Y0098882*
Y0098828*
X0647241*
Y0098774*
Y009872*
Y0098666*
X0647295*
Y0098612*
Y0098558*
Y0098504*
Y0098449*
X0647349*
Y0098395*
Y0098341*
Y0098287*
X0647403*
Y0098233*
Y0098179*
Y0098125*
X0647457*
Y0098071*
Y0098017*
Y0097963*
Y0097909*
X0647511*
Y0097855*
Y0097801*
Y0097747*
X0647565*
Y0097693*
Y0097638*
Y0097584*
Y009753*
X0647619*
Y0097476*
Y0097422*
Y0097368*
Y0097314*
X0647673*
Y009726*
Y0097206*
Y0097152*
Y0097098*
X0647727*
Y0097044*
Y009699*
Y0096936*
Y0096882*
X0647782*
Y0096828*
Y0096773*
Y0096719*
Y0096665*
Y0096611*
X0647835*
Y0096557*
Y0096503*
Y0096449*
Y0096395*
X064789*
Y0096341*
Y0096287*
Y0096233*
Y0096179*
Y0096125*
Y0096071*
X0647944*
Y0096017*
Y0095963*
Y0095908*
Y0095854*
Y00958*
X0647998*
Y0095746*
Y0095692*
Y0095638*
Y0095584*
Y009553*
Y0095476*
X0648052*
Y0095422*
Y0095368*
Y0095314*
Y009526*
Y0095206*
Y0095152*
Y0095098*
X0648106*
Y0095043*
Y009499*
Y0094935*
Y0094881*
Y0094827*
Y0094773*
Y0094719*
Y0094665*
Y0094611*
X064816*
Y0094557*
Y0094503*
Y0094449*
Y0094395*
Y0094341*
Y0094287*
Y0094233*
Y0094178*
Y0094125*
X0648214*
Y009407*
Y0094016*
Y0093962*
Y0093908*
Y0093854*
Y00938*
Y0093746*
Y0093692*
Y0093638*
Y0093584*
Y009353*
Y0093476*
Y0093422*
Y0093368*
Y0093313*
Y009326*
Y0093205*
X0648268*
Y0093151*
Y0093097*
Y0093043*
Y0092989*
Y0092935*
Y0092881*
Y0092827*
Y0092773*
Y0092719*
Y0092665*
Y0092611*
X0648917*
Y0092665*
Y0092719*
Y0092773*
Y0092827*
Y0092881*
Y0092935*
Y0092989*
Y0093043*
Y0093097*
Y0093151*
Y0093205*
Y009326*
X0648863*
Y0093313*
X0648917*
Y0093368*
Y0093422*
Y0093476*
X0648863*
Y009353*
Y0093584*
Y0093638*
Y0093692*
Y0093746*
Y00938*
Y0093854*
Y0093908*
Y0093962*
Y0094016*
Y009407*
Y0094125*
Y0094178*
Y0094233*
X0648809*
Y0094287*
Y0094341*
Y0094395*
Y0094449*
Y0094503*
Y0094557*
Y0094611*
Y0094665*
Y0094719*
Y0094773*
X0648755*
Y0094827*
Y0094881*
Y0094935*
Y009499*
Y0095043*
Y0095098*
Y0095152*
Y0095206*
X0648701*
Y009526*
Y0095314*
Y0095368*
Y0095422*
Y0095476*
Y009553*
Y0095584*
X0648646*
Y0095638*
Y0095692*
Y0095746*
Y00958*
Y0095854*
Y0095908*
X0648592*
Y0095963*
Y0096017*
Y0096071*
Y0096125*
Y0096179*
X0648538*
Y0096233*
Y0096287*
Y0096341*
Y0096395*
Y0096449*
X0648484*
Y0096503*
Y0096557*
Y0096611*
Y0096665*
Y0096719*
X064843*
Y0096773*
Y0096828*
Y0096882*
Y0096936*
Y009699*
X0648376*
Y0097044*
Y0097098*
Y0097152*
Y0097206*
X0648322*
Y009726*
Y0097314*
Y0097368*
Y0097422*
X0648268*
Y0097476*
Y009753*
Y0097584*
Y0097638*
X0648214*
Y0097693*
Y0097747*
Y0097801*
Y0097855*
X064816*
Y0097909*
Y0097963*
Y0098017*
X0648106*
Y0098071*
Y0098125*
Y0098179*
Y0098233*
X0648052*
Y0098287*
Y0098341*
Y0098395*
X0647998*
Y0098449*
Y0098504*
Y0098558*
Y0098612*
X0647944*
Y0098666*
Y009872*
Y0098774*
X064789*
Y0098828*
Y0098882*
Y0098936*
X0647835*
Y009899*
Y0099044*
Y0099098*
X0647782*
Y0099152*
Y0099206*
Y009926*
X0647727*
Y0099314*
Y0099369*
Y0099423*
X0647673*
Y0099477*
Y0099531*
X0647619*
Y0099585*
Y0099639*
Y0099693*
X0647565*
Y0099747*
Y0099801*
Y0099855*
X0647511*
Y0099909*
Y0099963*
X0647457*
Y0100017*
Y0100071*
Y0100125*
X0647403*
Y0100179*
Y0100233*
X0647349*
Y0100287*
Y0100342*
Y0100396*
X0647295*
Y010045*
Y0100504*
X0647241*
Y0100558*
Y0100612*
X0647187*
Y0100666*
Y010072*
Y0100774*
X0647133*
Y0100828*
Y0100882*
X0647079*
Y0100936*
Y010099*
X0647025*
Y0101044*
Y0101099*
X0646971*
Y0101153*
Y0101207*
Y0101261*
X0646916*
Y0101315*
Y0101369*
X0646862*
Y0101423*
Y0101477*
X0646808*
Y0101531*
Y0101585*
X0646754*
Y0101639*
Y0101693*
X06467*
Y0101747*
Y0101801*
X0646646*
Y0101855*
Y0101909*
X0646592*
Y0101963*
Y0102017*
X0646538*
Y0102072*
Y0102126*
X0646484*
Y010218*
Y0102234*
X064643*
Y0102288*
X0646376*
Y0102342*
Y0102396*
X0646322*
Y010245*
Y0102504*
X0646268*
Y0102558*
Y0102612*
X0646214*
Y0102666*
Y010272*
X064616*
Y0102774*
X0646105*
Y0102828*
Y0102883*
X0646052*
Y0102937*
Y0102991*
X0645997*
Y0103045*
X0645943*
Y0103099*
Y0103153*
X0645889*
Y0103207*
Y0103261*
X0645835*
Y0103315*
X0645781*
Y0103369*
Y0103423*
X0645727*
Y0103477*
Y0103531*
X0645673*
Y0103585*
X0645619*
Y0103639*
Y0103693*
X0645565*
Y0103747*
X0645511*
Y0103802*
Y0103856*
X0645457*
Y010391*
X0645403*
Y0103964*
Y0104018*
X0645349*
Y0104072*
X0645295*
Y0104126*
Y010418*
X064524*
Y0104234*
X0645187*
Y0104288*
Y0104342*
X0645132*
Y0104396*
X0645078*
Y010445*
X0645024*
Y0104504*
Y0104558*
X064497*
Y0104613*
X0644916*
Y0104667*
Y0104721*
X0644862*
Y0104775*
X0644808*
Y0104829*
X0644754*
Y0104883*
Y0104937*
X06447*
Y0104991*
X0644646*
Y0105045*
X0644592*
Y0105099*
X0644538*
Y0105153*
Y0105207*
X0644484*
Y0105261*
X064443*
Y0105315*
X0644376*
Y0105369*
Y0105423*
X0644321*
Y0105477*
X0644267*
Y0105532*
X0644213*
Y0105586*
X0644159*
Y010564*
X0644105*
Y0105694*
Y0105748*
X0644051*
Y0105802*
X0643997*
Y0105856*
X0643943*
Y010591*
X0643889*
Y0105964*
X0643835*
Y0106018*
Y0106072*
X0643781*
Y0106126*
X0643727*
Y010618*
X0643673*
Y0106234*
X0643619*
Y0106288*
X0643565*
Y0106342*
X0643511*
Y0106397*
X0643457*
Y0106451*
X0643402*
Y0106505*
Y0106559*
X0643348*
Y0106613*
X0643294*
Y0106667*
X064324*
Y0106721*
X0643186*
Y0106775*
X0643132*
Y0106829*
X0643078*
Y0106883*
X0643024*
Y0106937*
X064297*
Y0106991*
X0642916*
Y0107045*
X0642862*
Y0107099*
X0642808*
Y0107153*
X0642754*
Y0107208*
X06427*
Y0107262*
X0642646*
Y0107316*
X0642591*
Y010737*
X0642537*
Y0107424*
X0642483*
Y0107478*
X0642429*
Y0107532*
X0642375*
Y0107586*
X0642321*
Y010764*
X0642267*
Y0107694*
X0642159*
Y0107748*
X0642105*
Y0107802*
X0642051*
Y0107856*
X0641997*
Y010791*
X0641943*
Y0107964*
X0641889*
Y0108018*
X0641835*
Y0108072*
X0641781*
Y0108126*
X0641726*
Y0108181*
X0641618*
Y0108235*
X0641564*
Y0108289*
X064151*
Y0108343*
X0641456*
Y0108397*
X0641402*
Y0108451*
X0641294*
Y0108505*
X064124*
Y0108559*
X0641186*
Y0108613*
X0641132*
Y0108667*
X0641078*
Y0108721*
X064097*
Y0108775*
X0640916*
Y0108829*
X0640862*
Y0108883*
X0640753*
Y0108938*
X0640699*
Y0108992*
X0640645*
Y0109046*
X0640591*
Y01091*
X0640483*
Y0109154*
X0640429*
Y0109208*
X0640321*
Y0109262*
X0640267*
Y0109316*
X0640213*
Y010937*
X0640105*
Y0109424*
X0640051*
Y0109478*
X0639996*
Y0109532*
X0639888*
Y0109586*
X0639834*
Y010964*
X0639726*
Y0109694*
X0639672*
Y0109748*
X0639564*
Y0109802*
X063951*
Y0109856*
X0639402*
Y0109911*
X0639348*
Y0109965*
X063924*
Y0110019*
X0639131*
Y0110073*
X0639078*
Y0110127*
X0638969*
Y0110181*
X0638915*
Y0110235*
X0638807*
Y0110289*
X0638699*
Y0110343*
X0638645*
Y0110397*
X0638537*
Y0110451*
X0638429*
Y0110505*
X0638321*
Y0110559*
X0638267*
Y0110613*
X0638158*
Y0110668*
X063805*
Y0110722*
X0637942*
Y0110776*
X0637834*
Y011083*
X063778*
Y0110884*
X0637618*
Y0110938*
X0637564*
Y0110992*
X0637456*
Y0111046*
X0637293*
Y01111*
X0637185*
Y0111154*
X0637131*
Y0111208*
X0637023*
Y0111262*
X0636861*
Y0111316*
X0636753*
Y011137*
X0636645*
Y0111424*
X0636537*
Y0111478*
X0636428*
Y0111532*
X0636266*
Y0111586*
X0636158*
Y0111641*
X063605*
Y0111695*
X0635888*
Y0111749*
X063578*
Y0111803*
X0635617*
Y0111857*
X0635455*
Y0111911*
X0635347*
Y0111965*
X0635185*
Y0112019*
X0635023*
Y0112073*
X0634861*
Y0112127*
X0634753*
Y0112181*
X063459*
Y0112235*
X0634428*
Y0112289*
X0634212*
Y0112343*
X063405*
Y0112397*
X0633887*
Y0112452*
X0633671*
Y0112505*
X0633509*
Y011256*
X0633293*
Y0112614*
X0633077*
Y0112668*
X063286*
Y0112722*
X0632644*
Y0112776*
X0632374*
Y011283*
X0632103*
Y0112884*
X0631833*
Y0112938*
X0631509*
Y0112992*
X0631184*
Y0113046*
X0630752*
Y01131*
X0630319*
Y0113154*
X0629833*
Y0113208*
X0629022*
Y0113262*
G37*
G36*
X0621453Y00918D02*
X0621345D01*
Y0091746*
X0621291*
Y00918*
X0614804*
Y0091746*
X0614641*
Y0091692*
X0614479*
Y0091638*
X0614371*
Y0091584*
X0614317*
Y009153*
X0614263*
Y0091475*
X0614209*
Y0091421*
X0614155*
Y0091367*
X0614101*
Y0091313*
X0614047*
Y0091259*
X0613993*
Y0091205*
X0613939*
Y0091151*
X0613885*
Y0091097*
X0613831*
Y0091043*
X0613776*
Y0090989*
X0613722*
Y0090935*
X0613668*
Y0090881*
X0613614*
Y0090827*
X061356*
Y0090773*
X0613506*
Y0090719*
X0613452*
Y0090664*
X0613398*
Y009061*
X0613344*
Y0090556*
X061329*
Y0090502*
X0613236*
Y0090448*
X0613182*
Y0090394*
X0613128*
Y009034*
X0613074*
Y0090286*
X061302*
Y0090232*
X0612965*
Y0090178*
X0612912*
Y0090124*
X0612857*
Y009007*
Y0090016*
X0612803*
Y0089962*
Y0089908*
Y0089854*
Y0089799*
X0612749*
Y0089745*
Y0089691*
Y0089637*
Y0089583*
Y0089529*
Y0089475*
Y0089421*
Y0089367*
Y0089313*
Y0089259*
Y0089205*
Y0089151*
Y0089097*
Y0089043*
Y0088989*
Y0088934*
Y008888*
Y0088826*
Y0088772*
Y0088718*
Y0088664*
Y008861*
Y0088556*
Y0088502*
Y0088448*
Y0088394*
Y008834*
Y0088286*
Y0088232*
Y0088178*
Y0088124*
Y0088069*
Y0088016*
Y0087961*
Y0087907*
Y0087853*
Y0087799*
Y0087745*
Y0087691*
Y0087637*
Y0087583*
Y0087529*
Y0087475*
Y0087421*
Y0087367*
Y0087313*
Y0087259*
Y0087204*
Y0087151*
Y0087096*
Y0087042*
Y0086988*
Y0086934*
Y008688*
Y0086826*
Y0086772*
Y0086718*
Y0086664*
Y008661*
Y0086556*
Y0086502*
Y0086448*
Y0086394*
Y0086339*
Y0086286*
Y0086231*
Y0086177*
Y0086123*
Y0086069*
Y0086015*
Y0085961*
Y0085907*
Y0085853*
Y0085799*
Y0085745*
Y0085691*
Y0085637*
Y0085583*
Y0085529*
Y0085474*
Y0085421*
Y0085366*
Y0085312*
Y0085258*
Y0085204*
Y008515*
Y0085096*
Y0085042*
Y0084988*
Y0084934*
Y008488*
Y0084826*
Y0084772*
Y0084718*
Y0084664*
Y008461*
Y0084556*
Y0084501*
Y0084447*
Y0084393*
Y0084339*
Y0084285*
Y0084231*
Y0084177*
Y0084123*
Y0084069*
Y0084015*
Y0083961*
Y0083907*
Y0083853*
Y0083799*
Y0083745*
Y0083691*
Y0083636*
Y0083582*
Y0083528*
Y0083474*
Y008342*
Y0083366*
Y0083312*
Y0083258*
Y0083204*
Y008315*
Y0083096*
Y0083042*
Y0082988*
Y0082934*
Y008288*
Y0082825*
Y0082771*
Y0082717*
Y0082663*
Y0082609*
Y0082555*
Y0082501*
Y0082447*
Y0082393*
Y0082339*
Y0082285*
Y0082231*
Y0082177*
Y0082123*
Y0082069*
Y0082015*
Y008196*
X0612803*
Y0081906*
Y0081852*
Y0081798*
X0612857*
Y0081744*
Y008169*
X0612912*
Y0081636*
X0612965*
Y0081582*
X061302*
Y0081528*
X0613074*
Y0081474*
X0613128*
Y008142*
X0613182*
Y0081366*
X0613236*
Y0081312*
X061329*
Y0081258*
X0613344*
Y0081204*
X0613398*
Y008115*
X0613452*
Y0081095*
X0613506*
Y0081042*
X061356*
Y0080987*
X0613614*
Y0080933*
X0613668*
Y0080879*
X0613722*
Y0080825*
X0613776*
Y0080771*
X0613831*
Y0080717*
X0613885*
Y0080663*
X0613939*
Y0080609*
X0613993*
Y0080555*
X0614047*
Y0080501*
X0614101*
Y0080447*
X0614155*
Y0080393*
X0614209*
Y0080339*
X0614263*
Y0080285*
X0614317*
Y008023*
X0614371*
Y0080177*
X0614425*
Y0080122*
X0614533*
Y0080068*
X0614696*
Y0080014*
X0621561*
Y0080068*
X0621615*
Y0080122*
X0621669*
Y0080177*
X0621724*
Y008023*
Y0080285*
Y0080339*
Y0080393*
Y0080447*
Y0080501*
Y0080555*
Y0080609*
Y0080663*
Y0080717*
Y0080771*
Y0080825*
Y0080879*
Y0080933*
Y0080987*
Y0081042*
Y0081095*
Y008115*
Y0081204*
Y0081258*
Y0081312*
Y0081366*
Y008142*
Y0081474*
Y0081528*
Y0081582*
Y0081636*
Y008169*
Y0081744*
Y0081798*
Y0081852*
Y0081906*
Y008196*
Y0082015*
Y0082069*
Y0082123*
Y0082177*
Y0082231*
Y0082285*
Y0082339*
Y0082393*
Y0082447*
Y0082501*
Y0082555*
Y0082609*
Y0082663*
Y0082717*
X0621669*
Y0082771*
X0621615*
Y0082825*
X0621507*
Y008288*
X0615885*
Y0082934*
X0615777*
Y0082988*
Y0083042*
X0615723*
Y0083096*
Y008315*
Y0083204*
Y0083258*
Y0083312*
Y0083366*
Y008342*
Y0083474*
Y0083528*
Y0083582*
Y0083636*
Y0083691*
Y0083745*
Y0083799*
Y0083853*
Y0083907*
Y0083961*
Y0084015*
Y0084069*
Y0084123*
Y0084177*
Y0084231*
Y0084285*
Y0084339*
Y0084393*
Y0084447*
Y0084501*
Y0084556*
Y008461*
Y0084664*
Y0084718*
Y0084772*
Y0084826*
Y008488*
Y0084934*
Y0084988*
Y0085042*
Y0085096*
Y008515*
Y0085204*
Y0085258*
Y0085312*
Y0085366*
Y0085421*
Y0085474*
Y0085529*
Y0085583*
Y0085637*
Y0085691*
Y0085745*
Y0085799*
Y0085853*
Y0085907*
Y0085961*
Y0086015*
Y0086069*
Y0086123*
Y0086177*
Y0086231*
Y0086286*
Y0086339*
Y0086394*
Y0086448*
Y0086502*
Y0086556*
Y008661*
Y0086664*
Y0086718*
Y0086772*
Y0086826*
Y008688*
Y0086934*
Y0086988*
Y0087042*
Y0087096*
Y0087151*
Y0087204*
Y0087259*
Y0087313*
Y0087367*
Y0087421*
Y0087475*
Y0087529*
Y0087583*
Y0087637*
Y0087691*
Y0087745*
Y0087799*
Y0087853*
Y0087907*
Y0087961*
Y0088016*
Y0088069*
Y0088124*
Y0088178*
Y0088232*
Y0088286*
Y008834*
Y0088394*
Y0088448*
Y0088502*
Y0088556*
Y008861*
Y0088664*
Y0088718*
Y0088772*
X0615777*
Y0088826*
X0615831*
Y008888*
X0621183*
Y0088934*
X0621237*
Y008888*
X0621453*
Y0088934*
X0621615*
Y0088989*
X0621669*
Y0089043*
X0621724*
Y0089097*
Y0089151*
Y0089205*
Y0089259*
Y0089313*
Y0089367*
Y0089421*
Y0089475*
Y0089529*
Y0089583*
Y0089637*
Y0089691*
Y0089745*
Y0089799*
Y0089854*
Y0089908*
Y0089962*
Y0090016*
Y009007*
Y0090124*
Y0090178*
Y0090232*
Y0090286*
Y009034*
Y0090394*
Y0090448*
Y0090502*
Y0090556*
Y009061*
Y0090664*
Y0090719*
Y0090773*
Y0090827*
Y0090881*
Y0090935*
Y0090989*
Y0091043*
Y0091097*
Y0091151*
Y0091205*
Y0091259*
Y0091313*
Y0091367*
Y0091421*
Y0091475*
Y009153*
Y0091584*
Y0091638*
X0621669*
Y0091692*
X0621615*
Y0091746*
X0621453*
Y00918*
G37*
G36*
X0630914D02*
X0630157D01*
Y0091746*
X0630103*
Y0091692*
X0630049*
Y0091638*
X0629995*
Y0091584*
X0629941*
Y009153*
X0629887*
Y0091475*
X0629833*
Y0091421*
X0629779*
Y0091367*
X0629725*
Y0091313*
X0629671*
Y0091259*
X0629617*
Y0091205*
X0629563*
Y0091151*
X0629508*
Y0091097*
X0629454*
Y0091043*
X06294*
Y0090989*
X0629346*
Y0090935*
X0629292*
Y0090881*
X0629238*
Y0090827*
X0629184*
Y0090773*
X062913*
Y0090719*
X0629076*
Y0090664*
X0629022*
Y009061*
X0628968*
Y0090556*
X0628914*
Y0090502*
X062886*
Y0090448*
X0628806*
Y0090394*
X0628752*
Y009034*
X0628698*
Y0090286*
X0628644*
Y0090232*
X0628589*
Y0090178*
X0628535*
Y0090124*
X0628481*
Y009007*
X0628427*
Y0090016*
X0628373*
Y0089962*
X0628319*
Y0089908*
X0628265*
Y0089854*
X0628211*
Y0089799*
X0628157*
Y0089745*
X0628103*
Y0089691*
X0628049*
Y0089637*
X0627995*
Y0089583*
X0627941*
Y0089529*
X0627887*
Y0089475*
X0627833*
Y0089421*
X0627778*
Y0089367*
X0627725*
Y0089313*
X062767*
Y0089259*
X0627616*
Y0089205*
X0627562*
Y0089151*
X0629995*
Y0089097*
Y0089043*
Y0088989*
Y0088934*
Y008888*
Y0088826*
Y0088772*
Y0088718*
Y0088664*
Y008861*
Y0088556*
Y0088502*
Y0088448*
Y0088394*
Y008834*
Y0088286*
Y0088232*
Y0088178*
Y0088124*
Y0088069*
Y0088016*
Y0087961*
Y0087907*
Y0087853*
Y0087799*
Y0087745*
Y0087691*
Y0087637*
Y0087583*
Y0087529*
Y0087475*
Y0087421*
Y0087367*
Y0087313*
Y0087259*
Y0087204*
Y0087151*
Y0087096*
Y0087042*
Y0086988*
Y0086934*
Y008688*
Y0086826*
Y0086772*
Y0086718*
Y0086664*
Y008661*
Y0086556*
Y0086502*
Y0086448*
Y0086394*
Y0086339*
Y0086286*
Y0086231*
Y0086177*
X0626049*
Y0086231*
Y0086286*
Y0086339*
Y0086394*
Y0086448*
Y0086502*
Y0086556*
Y008661*
Y0086664*
Y0086718*
Y0086772*
Y0086826*
Y008688*
Y0086934*
Y0086988*
Y0087042*
Y0087096*
Y0087151*
Y0087204*
Y0087259*
Y0087313*
Y0087367*
X0625994*
Y0087313*
X062594*
Y0087259*
X0625886*
Y0087204*
X0625832*
Y0087151*
X0625778*
Y0087096*
X0625724*
Y0087042*
X062567*
Y0086988*
X0625616*
Y0086934*
X0625562*
Y008688*
X0625508*
Y0086826*
X0625454*
Y0086772*
X06254*
Y0086718*
X0625346*
Y0086664*
X0625292*
Y008661*
X0625238*
Y0086556*
X0625184*
Y0086502*
X062513*
Y0086448*
X0625075*
Y0086394*
X0625021*
Y0086339*
X0624967*
Y0086286*
X0624913*
Y0086231*
X0624859*
Y0086177*
X0624805*
Y0086123*
X0624751*
Y0086069*
X0624697*
Y0086015*
X0624643*
Y0085961*
X0624589*
Y0085907*
X0624535*
Y0085853*
X0624481*
Y0085799*
X0624427*
Y0085745*
X0624373*
Y0085691*
X0624319*
Y0085637*
X0624264*
Y0085583*
X062421*
Y0085529*
X0624156*
Y0085474*
X0624102*
Y0085421*
X0624048*
Y0085366*
X0623994*
Y0085312*
X062394*
Y0085258*
X0623886*
Y0085204*
X0623832*
Y008515*
X0623778*
Y0085096*
X0623724*
Y0085042*
X062367*
Y0084988*
X0623616*
Y0084934*
X0623562*
Y008488*
X0623508*
Y0084826*
X0623399*
Y0084772*
X0623345*
Y0084718*
X0623291*
Y0084664*
X0623237*
Y008461*
X0623183*
Y0084556*
X0623129*
Y0084501*
X0623075*
Y0084447*
Y0084393*
Y0084339*
Y0084285*
Y0084231*
Y0084177*
Y0084123*
Y0084069*
Y0084015*
Y0083961*
Y0083907*
Y0083853*
Y0083799*
Y0083745*
Y0083691*
Y0083636*
Y0083582*
Y0083528*
Y0083474*
Y008342*
Y0083366*
Y0083312*
Y0083258*
Y0083204*
Y008315*
Y0083096*
Y0083042*
Y0082988*
Y0082934*
Y008288*
Y0082825*
Y0082771*
Y0082717*
Y0082663*
Y0082609*
Y0082555*
Y0082501*
Y0082447*
Y0082393*
Y0082339*
Y0082285*
Y0082231*
Y0082177*
Y0082123*
Y0082069*
Y0082015*
Y008196*
Y0081906*
Y0081852*
Y0081798*
Y0081744*
Y008169*
Y0081636*
Y0081582*
Y0081528*
Y0081474*
Y008142*
Y0081366*
Y0081312*
Y0081258*
Y0081204*
Y008115*
Y0081095*
Y0081042*
Y0080987*
Y0080933*
Y0080879*
Y0080825*
Y0080771*
Y0080717*
Y0080663*
Y0080609*
Y0080555*
Y0080501*
Y0080447*
Y0080393*
Y0080339*
Y0080285*
Y008023*
Y0080177*
X0623129*
Y0080122*
X0623183*
Y0080068*
X0623291*
Y0080014*
X0625832*
Y0080068*
X062594*
Y0080122*
X0625994*
Y0080177*
Y008023*
X0626049*
Y0080285*
Y0080339*
Y0080393*
Y0080447*
Y0080501*
Y0080555*
Y0080609*
Y0080663*
Y0080717*
Y0080771*
Y0080825*
Y0080879*
Y0080933*
Y0080987*
Y0081042*
Y0081095*
Y008115*
Y0081204*
Y0081258*
Y0081312*
Y0081366*
Y008142*
Y0081474*
Y0081528*
Y0081582*
Y0081636*
Y008169*
Y0081744*
Y0081798*
Y0081852*
Y0081906*
Y008196*
Y0082015*
Y0082069*
Y0082123*
Y0082177*
Y0082231*
Y0082285*
Y0082339*
Y0082393*
Y0082447*
Y0082501*
Y0082555*
Y0082609*
Y0082663*
Y0082717*
Y0082771*
Y0082825*
Y008288*
Y0082934*
Y0082988*
Y0083042*
Y0083096*
Y008315*
Y0083204*
Y0083258*
Y0083312*
Y0083366*
Y008342*
Y0083474*
X0626103*
Y0083528*
Y0083582*
X0626211*
Y0083636*
X0629833*
Y0083582*
X0629941*
Y0083528*
Y0083474*
X0629995*
Y008342*
Y0083366*
Y0083312*
Y0083258*
Y0083204*
Y008315*
Y0083096*
Y0083042*
Y0082988*
Y0082934*
Y008288*
Y0082825*
Y0082771*
Y0082717*
Y0082663*
Y0082609*
Y0082555*
Y0082501*
Y0082447*
Y0082393*
Y0082339*
Y0082285*
Y0082231*
Y0082177*
Y0082123*
Y0082069*
Y0082015*
Y008196*
Y0081906*
Y0081852*
Y0081798*
Y0081744*
Y008169*
Y0081636*
Y0081582*
Y0081528*
Y0081474*
Y008142*
Y0081366*
Y0081312*
Y0081258*
Y0081204*
Y008115*
Y0081095*
Y0081042*
Y0080987*
Y0080933*
Y0080879*
Y0080825*
Y0080771*
Y0080717*
Y0080663*
Y0080609*
Y0080555*
Y0080501*
Y0080447*
Y0080393*
Y0080339*
Y0080285*
Y008023*
Y0080177*
X0630049*
Y0080122*
X0630103*
Y0080068*
X0630211*
Y0080014*
X0632752*
Y0080068*
X063286*
Y0080122*
X0632914*
Y0080177*
Y008023*
X0632969*
Y0080285*
Y0080339*
Y0080393*
Y0080447*
Y0080501*
Y0080555*
Y0080609*
Y0080663*
Y0080717*
Y0080771*
Y0080825*
Y0080879*
Y0080933*
Y0080987*
Y0081042*
Y0081095*
Y008115*
Y0081204*
Y0081258*
Y0081312*
Y0081366*
Y008142*
Y0081474*
Y0081528*
Y0081582*
Y0081636*
Y008169*
Y0081744*
Y0081798*
Y0081852*
Y0081906*
Y008196*
Y0082015*
Y0082069*
Y0082123*
Y0082177*
Y0082231*
Y0082285*
Y0082339*
Y0082393*
Y0082447*
Y0082501*
Y0082555*
Y0082609*
Y0082663*
Y0082717*
Y0082771*
Y0082825*
Y008288*
Y0082934*
Y0082988*
Y0083042*
Y0083096*
Y008315*
Y0083204*
Y0083258*
Y0083312*
Y0083366*
Y008342*
Y0083474*
Y0083528*
Y0083582*
Y0083636*
Y0083691*
Y0083745*
Y0083799*
Y0083853*
Y0083907*
Y0083961*
Y0084015*
Y0084069*
Y0084123*
Y0084177*
Y0084231*
Y0084285*
Y0084339*
Y0084393*
Y0084447*
Y0084501*
Y0084556*
Y008461*
Y0084664*
Y0084718*
Y0084772*
Y0084826*
Y008488*
Y0084934*
Y0084988*
Y0085042*
Y0085096*
Y008515*
Y0085204*
Y0085258*
Y0085312*
Y0085366*
Y0085421*
Y0085474*
Y0085529*
Y0085583*
Y0085637*
Y0085691*
Y0085745*
Y0085799*
Y0085853*
Y0085907*
Y0085961*
Y0086015*
Y0086069*
Y0086123*
Y0086177*
Y0086231*
Y0086286*
Y0086339*
Y0086394*
Y0086448*
Y0086502*
Y0086556*
Y008661*
Y0086664*
Y0086718*
Y0086772*
Y0086826*
Y008688*
Y0086934*
Y0086988*
Y0087042*
Y0087096*
Y0087151*
Y0087204*
Y0087259*
Y0087313*
Y0087367*
Y0087421*
Y0087475*
Y0087529*
Y0087583*
Y0087637*
Y0087691*
Y0087745*
Y0087799*
Y0087853*
Y0087907*
Y0087961*
Y0088016*
Y0088069*
Y0088124*
Y0088178*
Y0088232*
Y0088286*
Y008834*
Y0088394*
Y0088448*
Y0088502*
Y0088556*
Y008861*
Y0088664*
Y0088718*
Y0088772*
Y0088826*
Y008888*
Y0088934*
Y0088989*
Y0089043*
Y0089097*
Y0089151*
Y0089205*
Y0089259*
Y0089313*
Y0089367*
Y0089421*
Y0089475*
Y0089529*
Y0089583*
Y0089637*
Y0089691*
Y0089745*
X0632914*
Y0089799*
Y0089854*
Y0089908*
Y0089962*
X063286*
Y0090016*
Y009007*
Y0090124*
X0632806*
Y0090178*
X0632752*
Y0090232*
X0632698*
Y0090286*
X0632644*
Y009034*
X063259*
Y0090394*
X0632536*
Y0090448*
X0632482*
Y0090502*
X0632428*
Y0090556*
X0632374*
Y009061*
X063232*
Y0090664*
X0632266*
Y0090719*
X0632212*
Y0090773*
X0632158*
Y0090827*
X0632103*
Y0090881*
X0632049*
Y0090935*
X0631995*
Y0090989*
X0631941*
Y0091043*
X0631887*
Y0091097*
X0631833*
Y0091151*
X0631779*
Y0091205*
X0631725*
Y0091259*
X0631671*
Y0091313*
X0631617*
Y0091367*
X0631563*
Y0091421*
X0631509*
Y0091475*
X0631455*
Y009153*
X0631401*
Y0091584*
X0631347*
Y0091638*
X0631239*
Y0091692*
X063113*
Y0091746*
X0630914*
Y00918*
G37*
G36*
X0627184Y0110992D02*
X0626211D01*
Y0110938*
Y0110884*
Y011083*
Y0110776*
Y0110722*
Y0110668*
Y0110613*
Y0110559*
Y0110505*
Y0110451*
Y0110397*
Y0110343*
Y0110289*
Y0110235*
Y0110181*
Y0110127*
Y0110073*
Y0110019*
Y0109965*
Y0109911*
Y0109856*
Y0109802*
Y0109748*
Y0109694*
Y010964*
Y0109586*
Y0109532*
Y0109478*
Y0109424*
Y010937*
Y0109316*
Y0109262*
Y0109208*
Y0109154*
Y01091*
Y0109046*
Y0108992*
Y0108938*
Y0108883*
Y0108829*
Y0108775*
Y0108721*
Y0108667*
Y0108613*
Y0108559*
Y0108505*
Y0108451*
Y0108397*
Y0108343*
Y0108289*
Y0108235*
Y0108181*
Y0108126*
Y0108072*
Y0108018*
Y0107964*
Y010791*
Y0107856*
Y0107802*
Y0107748*
Y0107694*
Y010764*
Y0107586*
Y0107532*
Y0107478*
Y0107424*
Y010737*
Y0107316*
Y0107262*
Y0107208*
Y0107153*
Y0107099*
Y0107045*
Y0106991*
Y0106937*
Y0106883*
Y0106829*
Y0106775*
Y0106721*
Y0106667*
Y0106613*
Y0106559*
Y0106505*
Y0106451*
Y0106397*
Y0106342*
Y0106288*
Y0106234*
Y010618*
Y0106126*
Y0106072*
Y0106018*
Y0105964*
Y010591*
Y0105856*
Y0105802*
Y0105748*
Y0105694*
Y010564*
Y0105586*
Y0105532*
Y0105477*
Y0105423*
Y0105369*
Y0105315*
Y0105261*
Y0105207*
Y0105153*
Y0105099*
Y0105045*
Y0104991*
Y0104937*
Y0104883*
Y0104829*
Y0104775*
Y0104721*
Y0104667*
Y0104613*
Y0104558*
Y0104504*
Y010445*
Y0104396*
Y0104342*
Y0104288*
Y0104234*
Y010418*
Y0104126*
Y0104072*
Y0104018*
Y0103964*
Y010391*
Y0103856*
Y0103802*
Y0103747*
Y0103693*
Y0103639*
Y0103585*
Y0103531*
Y0103477*
Y0103423*
Y0103369*
Y0103315*
Y0103261*
Y0103207*
Y0103153*
Y0103099*
Y0103045*
Y0102991*
Y0102937*
Y0102883*
Y0102828*
Y0102774*
Y010272*
Y0102666*
Y0102612*
Y0102558*
Y0102504*
Y010245*
Y0102396*
Y0102342*
Y0102288*
Y0102234*
Y010218*
Y0102126*
Y0102072*
Y0102017*
Y0101963*
Y0101909*
Y0101855*
Y0101801*
Y0101747*
Y0101693*
Y0101639*
Y0101585*
Y0101531*
Y0101477*
Y0101423*
Y0101369*
Y0101315*
Y0101261*
Y0101207*
Y0101153*
Y0101099*
Y0101044*
Y010099*
Y0100936*
Y0100882*
Y0100828*
Y0100774*
Y010072*
Y0100666*
Y0100612*
Y0100558*
Y0100504*
Y010045*
Y0100396*
Y0100342*
Y0100287*
Y0100233*
Y0100179*
Y0100125*
Y0100071*
Y0100017*
Y0099963*
Y0099909*
Y0099855*
Y0099801*
Y0099747*
Y0099693*
Y0099639*
Y0099585*
Y0099531*
Y0099477*
Y0099423*
Y0099369*
Y0099314*
Y009926*
Y0099206*
Y0099152*
Y0099098*
Y0099044*
Y009899*
Y0098936*
Y0098882*
Y0098828*
Y0098774*
Y009872*
Y0098666*
Y0098612*
Y0098558*
Y0098504*
Y0098449*
Y0098395*
Y0098341*
Y0098287*
Y0098233*
Y0098179*
Y0098125*
Y0098071*
Y0098017*
Y0097963*
Y0097909*
Y0097855*
Y0097801*
Y0097747*
Y0097693*
Y0097638*
Y0097584*
Y009753*
Y0097476*
Y0097422*
Y0097368*
Y0097314*
Y009726*
Y0097206*
Y0097152*
Y0097098*
Y0097044*
Y009699*
Y0096936*
Y0096882*
Y0096828*
Y0096773*
Y0096719*
Y0096665*
Y0096611*
Y0096557*
Y0096503*
Y0096449*
Y0096395*
Y0096341*
Y0096287*
Y0096233*
Y0096179*
Y0096125*
Y0096071*
Y0096017*
Y0095963*
Y0095908*
Y0095854*
Y00958*
Y0095746*
Y0095692*
Y0095638*
Y0095584*
Y009553*
Y0095476*
Y0095422*
Y0095368*
Y0095314*
Y009526*
Y0095206*
Y0095152*
Y0095098*
Y0095043*
Y009499*
Y0094935*
Y0094881*
Y0094827*
Y0094773*
Y0094719*
Y0094665*
Y0094611*
Y0094557*
Y0094503*
Y0094449*
Y0094395*
Y0094341*
Y0094287*
Y0094233*
Y0094178*
Y0094125*
Y009407*
Y0094016*
Y0093962*
Y0093908*
Y0093854*
Y00938*
Y0093746*
Y0093692*
Y0093638*
Y0093584*
Y009353*
Y0093476*
Y0093422*
Y0093368*
Y0093313*
Y009326*
Y0093205*
Y0093151*
Y0093097*
X0626157*
Y0093043*
X0626103*
Y0092989*
X0626049*
Y0092935*
X0625994*
Y0092881*
X062594*
Y0092827*
X0625886*
Y0092773*
X0625832*
Y0092719*
X0625778*
Y0092665*
X0625724*
Y0092611*
X062567*
Y0092557*
X0625616*
Y0092503*
X0625562*
Y0092449*
X0625508*
Y0092395*
X0625454*
Y009234*
X06254*
Y0092286*
X0625346*
Y0092232*
X0625292*
Y0092178*
X0625184*
Y0092124*
X062513*
Y009207*
X0625075*
Y0092016*
X0625021*
Y0091962*
X0624967*
Y0091908*
X0624913*
Y0091854*
X0624859*
Y00918*
X0624805*
Y0091746*
X0624751*
Y0091692*
X0624697*
Y0091638*
X0624643*
Y0091584*
X0624589*
Y009153*
X0624535*
Y0091475*
X0624481*
Y0091421*
X0624427*
Y0091367*
X0624373*
Y0091313*
X0624319*
Y0091259*
X0624264*
Y0091205*
X062421*
Y0091151*
X0624156*
Y0091097*
X0624102*
Y0091043*
X0624048*
Y0090989*
X0623994*
Y0090935*
X062394*
Y0090881*
X0623886*
Y0090827*
X0623832*
Y0090773*
X0623778*
Y0090719*
X0623724*
Y0090664*
X062367*
Y009061*
X0623616*
Y0090556*
X0623562*
Y0090502*
X0623508*
Y0090448*
X0623454*
Y0090394*
X0623399*
Y009034*
X0623345*
Y0090286*
X0623291*
Y0090232*
X0623237*
Y0090178*
X0623183*
Y0090124*
X0623129*
Y009007*
X0623075*
Y0090016*
X0623021*
Y0089962*
X0622967*
Y0089908*
X0622913*
Y0089854*
X0622859*
Y0089799*
X0622805*
Y0089745*
X0622751*
Y0089691*
X0622697*
Y0089637*
X0622643*
Y0089583*
X0622589*
Y0089529*
X0622535*
Y0089475*
X062248*
Y0089421*
X0622426*
Y0089367*
X0622372*
Y0089313*
X0622318*
Y0089259*
X0622264*
Y0089205*
X062221*
Y0089151*
X0622156*
Y0089097*
X0622102*
Y0089043*
X0622048*
Y0088989*
X0621994*
Y0088934*
X062194*
Y008888*
X0621886*
Y0088826*
X0621832*
Y0088772*
X0621778*
Y0088718*
X0621724*
Y0088664*
X0621669*
Y008861*
X0621615*
Y0088556*
X0621507*
Y0088502*
X0621453*
Y0088448*
X0621399*
Y0088394*
X0621345*
Y008834*
X0621291*
Y0088286*
X0621237*
Y0088232*
X0621183*
Y0088178*
X0621129*
Y0088124*
X0621075*
Y0088069*
X0621021*
Y0088016*
X0620967*
Y0087961*
X0620913*
Y0087907*
X0620859*
Y0087853*
X0620805*
Y0087799*
X0620751*
Y0087745*
X0620696*
Y0087691*
X0620642*
Y0087637*
Y0087583*
X0620588*
Y0087529*
X0620534*
Y0087475*
Y0087421*
X062048*
Y0087367*
Y0087313*
X0620426*
Y0087259*
Y0087204*
Y0087151*
Y0087096*
Y0087042*
Y0086988*
Y0086934*
Y008688*
Y0086826*
Y0086772*
Y0086718*
Y0086664*
Y008661*
Y0086556*
Y0086502*
Y0086448*
Y0086394*
Y0086339*
Y0086286*
Y0086231*
Y0086177*
Y0086123*
Y0086069*
Y0086015*
Y0085961*
Y0085907*
Y0085853*
Y0085799*
Y0085745*
Y0085691*
Y0085637*
Y0085583*
Y0085529*
Y0085474*
Y0085421*
Y0085366*
Y0085312*
Y0085258*
Y0085204*
Y008515*
Y0085096*
Y0085042*
Y0084988*
Y0084934*
Y008488*
X062048*
Y0084826*
X0620534*
Y0084772*
Y0084718*
X0620588*
Y0084664*
X0620642*
Y008461*
Y0084556*
X0620696*
Y0084501*
X0620751*
Y0084447*
X0620805*
Y0084393*
X0620859*
Y0084339*
X0620913*
Y0084285*
X0620967*
Y0084231*
X0621021*
Y0084177*
X0621075*
Y0084123*
X0621129*
Y0084069*
X0621237*
Y0084123*
X0621291*
Y0084177*
X0621345*
Y0084231*
X0621399*
Y0084285*
X0621453*
Y0084339*
X0621507*
Y0084393*
X0621561*
Y0084447*
X0621615*
Y0084501*
X0621669*
Y0084556*
X0621724*
Y008461*
X0621778*
Y0084664*
X0621832*
Y0084718*
X0621886*
Y0084772*
X062194*
Y0084826*
X0621994*
Y008488*
X0622048*
Y0084934*
X0622102*
Y0084988*
X0622156*
Y0085042*
X062221*
Y0085096*
X0622264*
Y008515*
X0622318*
Y0085204*
X0622372*
Y0085258*
X0622426*
Y0085312*
X062248*
Y0085366*
X0622589*
Y0085421*
X0622643*
Y0085474*
X0622697*
Y0085529*
X0622751*
Y0085583*
X0622805*
Y0085637*
X0622859*
Y0085691*
X0622913*
Y0085745*
X0622967*
Y0085799*
X0623021*
Y0085853*
X0623075*
Y0085907*
X0623129*
Y0085961*
X0623183*
Y0086015*
X0623237*
Y0086069*
X0623291*
Y0086123*
X0623345*
Y0086177*
X0623399*
Y0086231*
X0623454*
Y0086286*
X0623508*
Y0086339*
X0623562*
Y0086394*
X0623616*
Y0086448*
X062367*
Y0086502*
X0623724*
Y0086556*
X0623778*
Y008661*
X0623832*
Y0086664*
X0623886*
Y0086718*
X062394*
Y0086772*
X0623994*
Y0086826*
X0624048*
Y008688*
X0624102*
Y0086934*
X0624156*
Y0086988*
X062421*
Y0087042*
X0624264*
Y0087096*
X0624319*
Y0087151*
X0624373*
Y0087204*
X0624427*
Y0087259*
X0624481*
Y0087313*
X0624535*
Y0087367*
X0624589*
Y0087421*
X0624643*
Y0087475*
X0624697*
Y0087529*
X0624751*
Y0087583*
X0624805*
Y0087637*
X0624859*
Y0087691*
X0624913*
Y0087745*
X0624967*
Y0087799*
X0625021*
Y0087853*
X0625075*
Y0087907*
X062513*
Y0087961*
X0625184*
Y0088016*
X0625238*
Y0088069*
X0625292*
Y0088124*
X0625346*
Y0088178*
X06254*
Y0088232*
X0625454*
Y0088286*
X0625508*
Y008834*
X0625562*
Y0088394*
X0625616*
Y0088448*
X062567*
Y0088502*
X0625724*
Y0088556*
X0625778*
Y008861*
X0625832*
Y0088664*
X0625886*
Y0088718*
X062594*
Y0088772*
X0625994*
Y0088826*
X0626049*
Y008888*
X0626103*
Y0088934*
X0626157*
Y0088989*
X0626211*
Y0089043*
X0626265*
Y0089097*
X0626319*
Y0089151*
X0626373*
Y0089205*
X0626427*
Y0089259*
X0626481*
Y0089313*
X0626535*
Y0089367*
X0626589*
Y0089421*
X0626643*
Y0089475*
X0626697*
Y0089529*
X0626751*
Y0089583*
X0626805*
Y0089637*
X062686*
Y0089691*
X0626913*
Y0089745*
X0626968*
Y0089799*
X0627022*
Y0089854*
X0627076*
Y0089908*
X0627184*
Y0089962*
X0627238*
Y0090016*
X0627292*
Y009007*
X0627346*
Y0090124*
X06274*
Y0090178*
X0627454*
Y0090232*
X0627508*
Y0090286*
X0627562*
Y009034*
X0627616*
Y0090394*
X062767*
Y0090448*
X0627725*
Y0090502*
X0627778*
Y0090556*
X0627833*
Y009061*
X0627887*
Y0090664*
X0627941*
Y0090719*
X0627995*
Y0090773*
X0628049*
Y0090827*
X0628103*
Y0090881*
X0628157*
Y0090935*
X0628211*
Y0090989*
X0628265*
Y0091043*
X0628319*
Y0091097*
X0628373*
Y0091151*
X0628427*
Y0091205*
X0628481*
Y0091259*
X0628535*
Y0091313*
X0628589*
Y0091367*
X0628644*
Y0091421*
X0628698*
Y0091475*
X0628752*
Y009153*
X0628806*
Y0091584*
Y0091638*
X062886*
Y0091692*
X0628914*
Y0091746*
Y00918*
X0628968*
Y0091854*
Y0091908*
X0629022*
Y0091962*
Y0092016*
X0629076*
Y009207*
Y0092124*
Y0092178*
Y0092232*
X062913*
Y0092286*
Y009234*
Y0092395*
Y0092449*
Y0092503*
Y0092557*
Y0092611*
Y0092665*
Y0092719*
Y0092773*
Y0092827*
Y0092881*
Y0092935*
Y0092989*
Y0093043*
Y0093097*
Y0093151*
Y0093205*
Y009326*
Y0093313*
Y0093368*
Y0093422*
Y0093476*
Y009353*
Y0093584*
Y0093638*
Y0093692*
Y0093746*
Y00938*
Y0093854*
Y0093908*
Y0093962*
Y0094016*
Y009407*
Y0094125*
Y0094178*
Y0094233*
Y0094287*
Y0094341*
Y0094395*
Y0094449*
Y0094503*
Y0094557*
Y0094611*
Y0094665*
Y0094719*
Y0094773*
Y0094827*
Y0094881*
Y0094935*
Y009499*
Y0095043*
Y0095098*
Y0095152*
Y0095206*
Y009526*
Y0095314*
Y0095368*
Y0095422*
Y0095476*
Y009553*
Y0095584*
Y0095638*
Y0095692*
Y0095746*
Y00958*
Y0095854*
Y0095908*
Y0095963*
Y0096017*
Y0096071*
Y0096125*
Y0096179*
Y0096233*
Y0096287*
Y0096341*
Y0096395*
Y0096449*
Y0096503*
Y0096557*
Y0096611*
Y0096665*
Y0096719*
Y0096773*
Y0096828*
Y0096882*
Y0096936*
Y009699*
Y0097044*
Y0097098*
Y0097152*
Y0097206*
Y009726*
Y0097314*
Y0097368*
Y0097422*
Y0097476*
Y009753*
Y0097584*
Y0097638*
Y0097693*
Y0097747*
Y0097801*
Y0097855*
Y0097909*
Y0097963*
Y0098017*
Y0098071*
Y0098125*
Y0098179*
Y0098233*
Y0098287*
Y0098341*
Y0098395*
Y0098449*
Y0098504*
Y0098558*
Y0098612*
Y0098666*
Y009872*
Y0098774*
Y0098828*
Y0098882*
Y0098936*
Y009899*
Y0099044*
Y0099098*
Y0099152*
Y0099206*
Y009926*
Y0099314*
Y0099369*
Y0099423*
Y0099477*
Y0099531*
Y0099585*
Y0099639*
Y0099693*
Y0099747*
Y0099801*
Y0099855*
Y0099909*
Y0099963*
Y0100017*
Y0100071*
Y0100125*
Y0100179*
Y0100233*
Y0100287*
Y0100342*
Y0100396*
Y010045*
Y0100504*
Y0100558*
Y0100612*
Y0100666*
Y010072*
Y0100774*
Y0100828*
Y0100882*
Y0100936*
Y010099*
Y0101044*
Y0101099*
Y0101153*
Y0101207*
Y0101261*
Y0101315*
Y0101369*
Y0101423*
Y0101477*
Y0101531*
Y0101585*
Y0101639*
Y0101693*
Y0101747*
Y0101801*
Y0101855*
Y0101909*
Y0101963*
Y0102017*
Y0102072*
Y0102126*
Y010218*
Y0102234*
Y0102288*
Y0102342*
Y0102396*
Y010245*
Y0102504*
Y0102558*
Y0102612*
Y0102666*
Y010272*
Y0102774*
Y0102828*
Y0102883*
Y0102937*
Y0102991*
Y0103045*
Y0103099*
Y0103153*
Y0103207*
Y0103261*
Y0103315*
Y0103369*
Y0103423*
Y0103477*
Y0103531*
Y0103585*
Y0103639*
Y0103693*
Y0103747*
Y0103802*
Y0103856*
Y010391*
Y0103964*
Y0104018*
Y0104072*
Y0104126*
Y010418*
Y0104234*
Y0104288*
Y0104342*
Y0104396*
Y010445*
Y0104504*
Y0104558*
Y0104613*
Y0104667*
Y0104721*
Y0104775*
Y0104829*
Y0104883*
Y0104937*
Y0104991*
Y0105045*
Y0105099*
Y0105153*
Y0105207*
Y0105261*
Y0105315*
Y0105369*
Y0105423*
Y0105477*
Y0105532*
Y0105586*
Y010564*
Y0105694*
Y0105748*
Y0105802*
Y0105856*
Y010591*
Y0105964*
Y0106018*
Y0106072*
Y0106126*
Y010618*
Y0106234*
Y0106288*
Y0106342*
Y0106397*
Y0106451*
Y0106505*
Y0106559*
Y0106613*
Y0106667*
Y0106721*
Y0106775*
Y0106829*
Y0106883*
Y0106937*
Y0106991*
Y0107045*
Y0107099*
Y0107153*
Y0107208*
Y0107262*
Y0107316*
Y010737*
Y0107424*
Y0107478*
Y0107532*
Y0107586*
Y010764*
Y0107694*
Y0107748*
Y0107802*
Y0107856*
Y010791*
Y0107964*
Y0108018*
Y0108072*
Y0108126*
Y0108181*
Y0108235*
Y0108289*
Y0108343*
Y0108397*
Y0108451*
Y0108505*
Y0108559*
Y0108613*
Y0108667*
Y0108721*
Y0108775*
Y0108829*
Y0108883*
Y0108938*
Y0108992*
Y0109046*
X0629076*
Y01091*
Y0109154*
Y0109208*
Y0109262*
X0629022*
Y0109316*
Y010937*
X0628968*
Y0109424*
X0628914*
Y0109478*
X062886*
Y0109532*
X0628806*
Y0109586*
X0628752*
Y010964*
X0628698*
Y0109694*
X0628644*
Y0109748*
X0628589*
Y0109802*
X0628535*
Y0109856*
X0628481*
Y0109911*
X0628427*
Y0109965*
X0628373*
Y0110019*
X0628319*
Y0110073*
X0628265*
Y0110127*
X0628211*
Y0110181*
X0628157*
Y0110235*
X0628103*
Y0110289*
X0628049*
Y0110343*
X0627995*
Y0110397*
X0627941*
Y0110451*
X0627887*
Y0110505*
X0627833*
Y0110559*
X0627778*
Y0110613*
X0627725*
Y0110668*
X062767*
Y0110722*
X0627616*
Y0110776*
X0627562*
Y011083*
X0627508*
Y0110884*
X06274*
Y0110938*
X0627184*
Y0110992*
G37*
G36*
X065335Y00918D02*
X0645889D01*
Y0091746*
X0645781*
Y0091692*
X0645727*
Y0091638*
X0645673*
Y0091584*
X0645619*
Y009153*
Y0091475*
Y0091421*
Y0091367*
Y0091313*
Y0091259*
Y0091205*
Y0091151*
Y0091097*
Y0091043*
Y0090989*
Y0090935*
Y0090881*
Y0090827*
Y0090773*
Y0090719*
Y0090664*
Y009061*
Y0090556*
Y0090502*
Y0090448*
Y0090394*
Y009034*
Y0090286*
Y0090232*
Y0090178*
Y0090124*
Y009007*
Y0090016*
Y0089962*
Y0089908*
Y0089854*
Y0089799*
Y0089745*
Y0089691*
Y0089637*
Y0089583*
Y0089529*
Y0089475*
Y0089421*
Y0089367*
Y0089313*
Y0089259*
Y0089205*
Y0089151*
Y0089097*
Y0089043*
Y0088989*
Y0088934*
Y008888*
Y0088826*
Y0088772*
Y0088718*
Y0088664*
Y008861*
Y0088556*
Y0088502*
Y0088448*
Y0088394*
Y008834*
Y0088286*
Y0088232*
Y0088178*
Y0088124*
Y0088069*
Y0088016*
Y0087961*
Y0087907*
Y0087853*
Y0087799*
Y0087745*
Y0087691*
Y0087637*
Y0087583*
Y0087529*
Y0087475*
Y0087421*
Y0087367*
Y0087313*
Y0087259*
Y0087204*
Y0087151*
Y0087096*
Y0087042*
Y0086988*
Y0086934*
Y008688*
Y0086826*
Y0086772*
Y0086718*
Y0086664*
Y008661*
Y0086556*
Y0086502*
Y0086448*
Y0086394*
Y0086339*
Y0086286*
Y0086231*
Y0086177*
Y0086123*
Y0086069*
Y0086015*
Y0085961*
Y0085907*
Y0085853*
Y0085799*
Y0085745*
Y0085691*
Y0085637*
Y0085583*
Y0085529*
Y0085474*
Y0085421*
Y0085366*
Y0085312*
Y0085258*
Y0085204*
Y008515*
Y0085096*
Y0085042*
Y0084988*
Y0084934*
Y008488*
Y0084826*
Y0084772*
Y0084718*
Y0084664*
Y008461*
Y0084556*
Y0084501*
Y0084447*
Y0084393*
Y0084339*
Y0084285*
Y0084231*
Y0084177*
Y0084123*
Y0084069*
Y0084015*
Y0083961*
Y0083907*
Y0083853*
Y0083799*
Y0083745*
Y0083691*
Y0083636*
Y0083582*
Y0083528*
Y0083474*
Y008342*
Y0083366*
Y0083312*
Y0083258*
Y0083204*
Y008315*
Y0083096*
Y0083042*
Y0082988*
Y0082934*
Y008288*
Y0082825*
Y0082771*
Y0082717*
Y0082663*
Y0082609*
Y0082555*
Y0082501*
Y0082447*
Y0082393*
Y0082339*
Y0082285*
Y0082231*
Y0082177*
Y0082123*
Y0082069*
Y0082015*
Y008196*
Y0081906*
Y0081852*
Y0081798*
Y0081744*
Y008169*
Y0081636*
Y0081582*
Y0081528*
Y0081474*
Y008142*
Y0081366*
Y0081312*
Y0081258*
Y0081204*
Y008115*
Y0081095*
Y0081042*
Y0080987*
Y0080933*
Y0080879*
Y0080825*
Y0080771*
Y0080717*
Y0080663*
Y0080609*
Y0080555*
Y0080501*
Y0080447*
Y0080393*
Y0080339*
Y0080285*
Y008023*
Y0080177*
X0645673*
Y0080122*
X0645727*
Y0080068*
X0645781*
Y0080014*
X0653512*
Y0080068*
X0653728*
Y0080122*
X0653836*
Y0080177*
X0653891*
Y008023*
X0653944*
Y0080285*
X0653999*
Y0080339*
X0654053*
Y0080393*
X0654107*
Y0080447*
X0654161*
Y0080501*
X0654215*
Y0080555*
X0654269*
Y0080609*
X0654323*
Y0080663*
X0654377*
Y0080717*
X0654431*
Y0080771*
X0654485*
Y0080825*
X0654539*
Y0080879*
X0654593*
Y0080933*
X0654647*
Y0080987*
X0654701*
Y0081042*
X0654755*
Y0081095*
X065481*
Y008115*
X0654864*
Y0081204*
X0654918*
Y0081258*
X0654972*
Y0081312*
X0655026*
Y0081366*
X065508*
Y008142*
X0655134*
Y0081474*
X0655188*
Y0081528*
X0655242*
Y0081582*
X0655296*
Y0081636*
X065535*
Y008169*
X0655404*
Y0081744*
Y0081798*
Y0081852*
X0655458*
Y0081906*
Y008196*
Y0082015*
Y0082069*
X0655512*
Y0082123*
Y0082177*
Y0082231*
Y0082285*
Y0082339*
Y0082393*
Y0082447*
Y0082501*
Y0082555*
Y0082609*
Y0082663*
Y0082717*
Y0082771*
Y0082825*
Y008288*
Y0082934*
Y0082988*
Y0083042*
Y0083096*
Y008315*
Y0083204*
Y0083258*
Y0083312*
Y0083366*
Y008342*
Y0083474*
Y0083528*
Y0083582*
Y0083636*
Y0083691*
Y0083745*
Y0083799*
Y0083853*
Y0083907*
Y0083961*
Y0084015*
Y0084069*
Y0084123*
Y0084177*
Y0084231*
Y0084285*
Y0084339*
Y0084393*
Y0084447*
Y0084501*
Y0084556*
Y008461*
Y0084664*
Y0084718*
Y0084772*
Y0084826*
Y008488*
Y0084934*
Y0084988*
Y0085042*
Y0085096*
Y008515*
Y0085204*
Y0085258*
Y0085312*
Y0085366*
Y0085421*
Y0085474*
Y0085529*
Y0085583*
Y0085637*
Y0085691*
Y0085745*
Y0085799*
Y0085853*
Y0085907*
Y0085961*
Y0086015*
Y0086069*
Y0086123*
Y0086177*
Y0086231*
Y0086286*
Y0086339*
Y0086394*
Y0086448*
Y0086502*
Y0086556*
Y008661*
Y0086664*
Y0086718*
Y0086772*
Y0086826*
Y008688*
Y0086934*
Y0086988*
Y0087042*
Y0087096*
Y0087151*
Y0087204*
Y0087259*
Y0087313*
Y0087367*
Y0087421*
Y0087475*
Y0087529*
Y0087583*
Y0087637*
Y0087691*
Y0087745*
Y0087799*
Y0087853*
Y0087907*
Y0087961*
Y0088016*
Y0088069*
Y0088124*
Y0088178*
Y0088232*
Y0088286*
Y008834*
Y0088394*
Y0088448*
Y0088502*
Y0088556*
Y008861*
Y0088664*
Y0088718*
Y0088772*
Y0088826*
Y008888*
Y0088934*
Y0088989*
Y0089043*
Y0089097*
Y0089151*
Y0089205*
Y0089259*
Y0089313*
Y0089367*
Y0089421*
Y0089475*
Y0089529*
Y0089583*
Y0089637*
Y0089691*
Y0089745*
X0655458*
Y0089799*
Y0089854*
Y0089908*
Y0089962*
X0655404*
Y0090016*
Y009007*
X065535*
Y0090124*
X0655296*
Y0090178*
X0655242*
Y0090232*
X0655188*
Y0090286*
X0655134*
Y009034*
X065508*
Y0090394*
X0655026*
Y0090448*
X0654972*
Y0090502*
X0654918*
Y0090556*
X0654864*
Y009061*
X065481*
Y0090664*
X0654755*
Y0090719*
X0654701*
Y0090773*
X0654647*
Y0090827*
X0654593*
Y0090881*
X0654539*
Y0090935*
X0654485*
Y0090989*
X0654431*
Y0091043*
X0654377*
Y0091097*
X0654323*
Y0091151*
X0654269*
Y0091205*
X0654215*
Y0091259*
X0654161*
Y0091313*
X0654107*
Y0091367*
X0654053*
Y0091421*
X0653999*
Y0091475*
X0653944*
Y009153*
X0653891*
Y0091584*
X0653836*
Y0091638*
X0653782*
Y0091692*
X065362*
Y0091746*
X065335*
Y00918*
G37*
G36*
X0641835D02*
X0634374D01*
Y0091746*
X0634266*
Y0091692*
X0634212*
Y0091638*
X0634158*
Y0091584*
Y009153*
Y0091475*
X0634104*
Y0091421*
Y0091367*
Y0091313*
Y0091259*
Y0091205*
Y0091151*
Y0091097*
Y0091043*
Y0090989*
Y0090935*
Y0090881*
Y0090827*
Y0090773*
Y0090719*
Y0090664*
Y009061*
Y0090556*
Y0090502*
Y0090448*
Y0090394*
Y009034*
Y0090286*
Y0090232*
Y0090178*
Y0090124*
Y009007*
Y0090016*
Y0089962*
Y0089908*
Y0089854*
Y0089799*
Y0089745*
Y0089691*
Y0089637*
Y0089583*
Y0089529*
Y0089475*
Y0089421*
Y0089367*
Y0089313*
Y0089259*
Y0089205*
Y0089151*
Y0089097*
Y0089043*
Y0088989*
Y0088934*
Y008888*
Y0088826*
Y0088772*
Y0088718*
Y0088664*
Y008861*
Y0088556*
Y0088502*
Y0088448*
Y0088394*
Y008834*
Y0088286*
Y0088232*
Y0088178*
Y0088124*
Y0088069*
Y0088016*
Y0087961*
Y0087907*
Y0087853*
Y0087799*
Y0087745*
Y0087691*
Y0087637*
Y0087583*
Y0087529*
Y0087475*
Y0087421*
Y0087367*
Y0087313*
Y0087259*
Y0087204*
Y0087151*
Y0087096*
Y0087042*
Y0086988*
Y0086934*
Y008688*
Y0086826*
Y0086772*
Y0086718*
Y0086664*
Y008661*
Y0086556*
Y0086502*
Y0086448*
Y0086394*
Y0086339*
Y0086286*
Y0086231*
Y0086177*
Y0086123*
Y0086069*
Y0086015*
Y0085961*
Y0085907*
Y0085853*
Y0085799*
Y0085745*
Y0085691*
Y0085637*
Y0085583*
Y0085529*
Y0085474*
Y0085421*
Y0085366*
Y0085312*
Y0085258*
Y0085204*
Y008515*
Y0085096*
Y0085042*
Y0084988*
Y0084934*
Y008488*
Y0084826*
Y0084772*
Y0084718*
Y0084664*
Y008461*
Y0084556*
Y0084501*
Y0084447*
Y0084393*
Y0084339*
Y0084285*
Y0084231*
Y0084177*
Y0084123*
Y0084069*
Y0084015*
Y0083961*
Y0083907*
Y0083853*
Y0083799*
Y0083745*
Y0083691*
Y0083636*
Y0083582*
Y0083528*
Y0083474*
Y008342*
Y0083366*
Y0083312*
Y0083258*
Y0083204*
Y008315*
Y0083096*
Y0083042*
Y0082988*
Y0082934*
Y008288*
Y0082825*
Y0082771*
Y0082717*
Y0082663*
Y0082609*
Y0082555*
Y0082501*
Y0082447*
Y0082393*
Y0082339*
Y0082285*
Y0082231*
Y0082177*
Y0082123*
Y0082069*
Y0082015*
Y008196*
Y0081906*
Y0081852*
Y0081798*
Y0081744*
Y008169*
Y0081636*
Y0081582*
Y0081528*
Y0081474*
Y008142*
Y0081366*
Y0081312*
Y0081258*
Y0081204*
Y008115*
Y0081095*
Y0081042*
Y0080987*
Y0080933*
Y0080879*
Y0080825*
Y0080771*
Y0080717*
Y0080663*
Y0080609*
Y0080555*
Y0080501*
Y0080447*
Y0080393*
X0634158*
Y0080339*
X0634104*
Y0080285*
X0634158*
Y008023*
Y0080177*
Y0080122*
X0634212*
Y0080068*
X063432*
Y0080014*
X0636969*
Y0080068*
X0637023*
Y0080122*
X0637077*
Y0080177*
Y008023*
Y0080285*
X0637131*
Y0080339*
Y0080393*
Y0080447*
Y0080501*
Y0080555*
Y0080609*
Y0080663*
Y0080717*
Y0080771*
Y0080825*
Y0080879*
Y0080933*
Y0080987*
Y0081042*
Y0081095*
Y008115*
Y0081204*
Y0081258*
Y0081312*
Y0081366*
Y008142*
Y0081474*
Y0081528*
Y0081582*
Y0081636*
Y008169*
Y0081744*
Y0081798*
Y0081852*
Y0081906*
Y008196*
Y0082015*
Y0082069*
Y0082123*
Y0082177*
Y0082231*
Y0082285*
Y0082339*
Y0082393*
Y0082447*
Y0082501*
Y0082555*
Y0082609*
Y0082663*
Y0082717*
Y0082771*
Y0082825*
Y008288*
Y0082934*
Y0082988*
Y0083042*
Y0083096*
Y008315*
Y0083204*
X0637077*
Y0083258*
X0637131*
Y0083312*
Y0083366*
Y008342*
Y0083474*
Y0083528*
X0639186*
Y0083474*
Y008342*
X063924*
Y0083366*
Y0083312*
X0639294*
Y0083258*
X0639348*
Y0083204*
Y008315*
X0639402*
Y0083096*
Y0083042*
X0639456*
Y0082988*
X063951*
Y0082934*
Y008288*
X0639564*
Y0082825*
Y0082771*
X0639618*
Y0082717*
Y0082663*
X0639672*
Y0082609*
X0639726*
Y0082555*
Y0082501*
X063978*
Y0082447*
Y0082393*
X0639834*
Y0082339*
X0639888*
Y0082285*
Y0082231*
X0639943*
Y0082177*
Y0082123*
X0639996*
Y0082069*
X0640051*
Y0082015*
Y008196*
X0640105*
Y0081906*
Y0081852*
X0640159*
Y0081798*
Y0081744*
X0640213*
Y008169*
X0640267*
Y0081636*
Y0081582*
X0640321*
Y0081528*
Y0081474*
X0640375*
Y008142*
X0640429*
Y0081366*
Y0081312*
X0640483*
Y0081258*
Y0081204*
X0640537*
Y008115*
X0640591*
Y0081095*
Y0081042*
X0640645*
Y0080987*
Y0080933*
X0640699*
Y0080879*
X0640753*
Y0080825*
Y0080771*
X0640807*
Y0080717*
Y0080663*
X0640862*
Y0080609*
Y0080555*
X0640916*
Y0080501*
X064097*
Y0080447*
Y0080393*
X0641024*
Y0080339*
Y0080285*
X0641078*
Y008023*
X0641132*
Y0080177*
X0641186*
Y0080122*
X064124*
Y0080068*
X0641348*
Y0080014*
X0644376*
Y0080068*
X064443*
Y0080122*
Y0080177*
Y008023*
Y0080285*
X0644376*
Y0080339*
X0644321*
Y0080393*
Y0080447*
X0644267*
Y0080501*
Y0080555*
X0644213*
Y0080609*
X0644159*
Y0080663*
Y0080717*
X0644105*
Y0080771*
Y0080825*
X0644051*
Y0080879*
X0643997*
Y0080933*
Y0080987*
X0643943*
Y0081042*
Y0081095*
X0643889*
Y008115*
X0643835*
Y0081204*
Y0081258*
X0643781*
Y0081312*
Y0081366*
X0643727*
Y008142*
X0643673*
Y0081474*
Y0081528*
X0643619*
Y0081582*
Y0081636*
X0643565*
Y008169*
X0643511*
Y0081744*
Y0081798*
X0643457*
Y0081852*
Y0081906*
X0643402*
Y008196*
X0643348*
Y0082015*
Y0082069*
X0643294*
Y0082123*
Y0082177*
X064324*
Y0082231*
X0643186*
Y0082285*
Y0082339*
X0643132*
Y0082393*
Y0082447*
X0643078*
Y0082501*
X0643024*
Y0082555*
Y0082609*
X064297*
Y0082663*
Y0082717*
X0642916*
Y0082771*
X0642862*
Y0082825*
Y008288*
X0642808*
Y0082934*
Y0082988*
X0642754*
Y0083042*
X06427*
Y0083096*
Y008315*
X0642646*
Y0083204*
Y0083258*
X0642591*
Y0083312*
Y0083366*
X0642537*
Y008342*
X0642483*
Y0083474*
Y0083528*
X0642429*
Y0083582*
Y0083636*
X0642375*
Y0083691*
X0642321*
Y0083745*
Y0083799*
X0642375*
Y0083853*
X0642429*
Y0083907*
X0642483*
Y0083961*
X0642537*
Y0084015*
X0642591*
Y0084069*
X0642646*
Y0084123*
X06427*
Y0084177*
X0642754*
Y0084231*
X0642808*
Y0084285*
X0642862*
Y0084339*
X0642916*
Y0084393*
X064297*
Y0084447*
X0643024*
Y0084501*
X0643078*
Y0084556*
X0643132*
Y008461*
X0643186*
Y0084664*
X064324*
Y0084718*
X0643294*
Y0084772*
X0643348*
Y0084826*
X0643402*
Y008488*
X0643457*
Y0084934*
X0643511*
Y0084988*
X0643565*
Y0085042*
Y0085096*
X0643619*
Y008515*
X0643673*
Y0085204*
X0643727*
Y0085258*
X0643781*
Y0085312*
X0643835*
Y0085366*
X0643889*
Y0085421*
Y0085474*
X0643943*
Y0085529*
Y0085583*
X0643997*
Y0085637*
Y0085691*
Y0085745*
Y0085799*
Y0085853*
Y0085907*
Y0085961*
Y0086015*
Y0086069*
Y0086123*
Y0086177*
Y0086231*
Y0086286*
Y0086339*
Y0086394*
Y0086448*
Y0086502*
Y0086556*
Y008661*
Y0086664*
Y0086718*
Y0086772*
Y0086826*
Y008688*
Y0086934*
Y0086988*
Y0087042*
Y0087096*
Y0087151*
Y0087204*
Y0087259*
Y0087313*
Y0087367*
Y0087421*
Y0087475*
Y0087529*
Y0087583*
Y0087637*
Y0087691*
Y0087745*
Y0087799*
Y0087853*
Y0087907*
Y0087961*
Y0088016*
Y0088069*
Y0088124*
Y0088178*
Y0088232*
Y0088286*
Y008834*
Y0088394*
Y0088448*
Y0088502*
Y0088556*
Y008861*
Y0088664*
Y0088718*
Y0088772*
Y0088826*
Y008888*
Y0088934*
Y0088989*
Y0089043*
Y0089097*
Y0089151*
Y0089205*
Y0089259*
Y0089313*
Y0089367*
Y0089421*
Y0089475*
Y0089529*
Y0089583*
Y0089637*
Y0089691*
Y0089745*
Y0089799*
Y0089854*
X0643943*
Y0089908*
Y0089962*
Y0090016*
X0643889*
Y009007*
Y0090124*
X0643835*
Y0090178*
X0643781*
Y0090232*
X0643727*
Y0090286*
X0643673*
Y009034*
X0643619*
Y0090394*
X0643565*
Y0090448*
X0643511*
Y0090502*
X0643457*
Y0090556*
X0643402*
Y009061*
X0643348*
Y0090664*
X0643294*
Y0090719*
X064324*
Y0090773*
X0643186*
Y0090827*
X0643132*
Y0090881*
X0643078*
Y0090935*
X0643024*
Y0090989*
X064297*
Y0091043*
X0642916*
Y0091097*
X0642862*
Y0091151*
X0642808*
Y0091205*
X0642754*
Y0091259*
X06427*
Y0091313*
X0642646*
Y0091367*
X0642591*
Y0091421*
X0642537*
Y0091475*
X0642483*
Y009153*
X0642429*
Y0091584*
X0642375*
Y0091638*
X0642267*
Y0091692*
X0642105*
Y0091746*
X0641835*
Y00918*
G37*
G36*
X0607776Y0091746D02*
X0607127D01*
Y0091692*
Y0091638*
Y0091584*
Y009153*
Y0091475*
Y0091421*
Y0091367*
Y0091313*
Y0091259*
Y0091205*
Y0091151*
X0607181*
Y0091097*
Y0091043*
Y0090989*
Y0090935*
Y0090881*
Y0090827*
Y0090773*
Y0090719*
Y0090664*
Y009061*
Y0090556*
X0607235*
Y0090502*
X0607181*
Y0090448*
X0607235*
Y0090394*
Y009034*
Y0090286*
Y0090232*
Y0090178*
Y0090124*
Y009007*
Y0090016*
Y0089962*
Y0089908*
X0607289*
Y0089854*
Y0089799*
Y0089745*
Y0089691*
Y0089637*
Y0089583*
Y0089529*
Y0089475*
X0607343*
Y0089421*
Y0089367*
Y0089313*
Y0089259*
Y0089205*
Y0089151*
Y0089097*
X0607397*
Y0089043*
Y0088989*
Y0088934*
Y008888*
Y0088826*
Y0088772*
X0607451*
Y0088718*
Y0088664*
Y008861*
Y0088556*
Y0088502*
X0607505*
Y0088448*
Y0088394*
Y008834*
Y0088286*
Y0088232*
X0607559*
Y0088178*
Y0088124*
Y0088069*
Y0088016*
Y0087961*
X0607613*
Y0087907*
Y0087853*
Y0087799*
Y0087745*
Y0087691*
X0607667*
Y0087637*
Y0087583*
Y0087529*
Y0087475*
X0607722*
Y0087421*
Y0087367*
Y0087313*
Y0087259*
X0607776*
Y0087204*
Y0087151*
Y0087096*
Y0087042*
X060783*
Y0086988*
Y0086934*
Y008688*
Y0086826*
X0607884*
Y0086772*
Y0086718*
Y0086664*
X0607938*
Y008661*
Y0086556*
Y0086502*
Y0086448*
X0607992*
Y0086394*
Y0086339*
Y0086286*
X0608046*
Y0086231*
Y0086177*
Y0086123*
X06081*
Y0086069*
Y0086015*
Y0085961*
X0608154*
Y0085907*
Y0085853*
Y0085799*
X0608208*
Y0085745*
Y0085691*
Y0085637*
X0608262*
Y0085583*
Y0085529*
Y0085474*
X0608316*
Y0085421*
Y0085366*
Y0085312*
X060837*
Y0085258*
Y0085204*
Y008515*
X0608424*
Y0085096*
Y0085042*
Y0084988*
X0608478*
Y0084934*
Y008488*
X0608532*
Y0084826*
Y0084772*
Y0084718*
X0608587*
Y0084664*
Y008461*
X0608641*
Y0084556*
Y0084501*
Y0084447*
X0608695*
Y0084393*
Y0084339*
X0608749*
Y0084285*
Y0084231*
Y0084177*
X0608803*
Y0084123*
Y0084069*
X0608857*
Y0084015*
Y0083961*
X0608911*
Y0083907*
Y0083853*
Y0083799*
X0608965*
Y0083745*
Y0083691*
X0609019*
Y0083636*
Y0083582*
X0609073*
Y0083528*
Y0083474*
X0609127*
Y008342*
Y0083366*
X0609181*
Y0083312*
Y0083258*
X0609235*
Y0083204*
Y008315*
X0609289*
Y0083096*
Y0083042*
X0609343*
Y0082988*
Y0082934*
X0609397*
Y008288*
Y0082825*
X0609451*
Y0082771*
Y0082717*
X0609506*
Y0082663*
Y0082609*
X060956*
Y0082555*
Y0082501*
X0609614*
Y0082447*
Y0082393*
X0609668*
Y0082339*
X0609722*
Y0082285*
Y0082231*
X0609776*
Y0082177*
Y0082123*
X060983*
Y0082069*
Y0082015*
X0609884*
Y008196*
Y0081906*
X0609938*
Y0081852*
X0609992*
Y0081798*
Y0081744*
X0610046*
Y008169*
Y0081636*
X06101*
Y0081582*
Y0081528*
X0610154*
Y0081474*
X0610208*
Y008142*
Y0081366*
X0610262*
Y0081312*
X0610317*
Y0081258*
Y0081204*
X0610371*
Y008115*
Y0081095*
X0610425*
Y0081042*
X0610479*
Y0080987*
Y0080933*
X0610533*
Y0080879*
X0610587*
Y0080825*
Y0080771*
X0610641*
Y0080717*
X0610695*
Y0080663*
Y0080609*
X0610749*
Y0080555*
X0610803*
Y0080501*
Y0080447*
X0610857*
Y0080393*
X0610911*
Y0080339*
X0610965*
Y0080285*
Y008023*
X0611019*
Y0080177*
X0611073*
Y0080122*
Y0080068*
X0611127*
Y0080014*
X0611181*
Y007996*
X0611236*
Y0079906*
Y0079852*
X061129*
Y0079798*
X0611344*
Y0079744*
X0611398*
Y007969*
Y0079636*
X0611452*
Y0079582*
X0611506*
Y0079528*
X061156*
Y0079474*
X0611614*
Y007942*
Y0079365*
X0611668*
Y0079312*
X0611722*
Y0079257*
X0611776*
Y0079203*
X061183*
Y0079149*
Y0079095*
X0611884*
Y0079041*
X0611938*
Y0078987*
X0611992*
Y0078933*
X0612046*
Y0078879*
Y0078825*
X0612101*
Y0078771*
X0612155*
Y0078717*
X0612209*
Y0078663*
X0612263*
Y0078609*
X0612317*
Y0078555*
X0612371*
Y00785*
X0612425*
Y0078447*
Y0078392*
X0612479*
Y0078338*
X0612533*
Y0078284*
X0612587*
Y007823*
X0612641*
Y0078176*
X0612695*
Y0078122*
X0612749*
Y0078068*
X0612803*
Y0078014*
X0612857*
Y007796*
X0612912*
Y0077906*
X0612965*
Y0077852*
X061302*
Y0077798*
X0613074*
Y0077744*
X0613128*
Y007769*
X0613182*
Y0077636*
X0613236*
Y0077582*
X061329*
Y0077527*
X0613344*
Y0077473*
X0613398*
Y0077419*
X0613452*
Y0077365*
X0613506*
Y0077311*
X061356*
Y0077257*
X0613614*
Y0077203*
X0613668*
Y0077149*
X0613722*
Y0077095*
X0613776*
Y0077041*
X0613831*
Y0076987*
X0613885*
Y0076933*
X0613939*
Y0076879*
X0613993*
Y0076825*
X0614047*
Y0076771*
X0614155*
Y0076717*
X0614209*
Y0076662*
X0614263*
Y0076608*
X0614317*
Y0076554*
X0614371*
Y00765*
X0614425*
Y0076446*
X0614479*
Y0076392*
X0614587*
Y0076338*
X0614641*
Y0076284*
X0614696*
Y007623*
X061475*
Y0076176*
X0614804*
Y0076122*
X0614912*
Y0076068*
X0614966*
Y0076014*
X061502*
Y007596*
X0615074*
Y0075906*
X0615182*
Y0075852*
X0615236*
Y0075797*
X061529*
Y0075743*
X0615398*
Y0075689*
X0615452*
Y0075635*
X0615507*
Y0075581*
X0615615*
Y0075527*
X0615669*
Y0075473*
X0615723*
Y0075419*
X0615831*
Y0075365*
X0615885*
Y0075311*
X0615993*
Y0075257*
X0616047*
Y0075203*
X0616101*
Y0075149*
X0616209*
Y0075095*
X0616263*
Y0075041*
X0616371*
Y0074986*
X0616426*
Y0074932*
X0616534*
Y0074878*
X0616588*
Y0074824*
X0616696*
Y007477*
X061675*
Y0074716*
X0616858*
Y0074662*
X0616966*
Y0074608*
X061702*
Y0074554*
X0617128*
Y00745*
X0617182*
Y0074446*
X061729*
Y0074392*
X0617399*
Y0074338*
X0617453*
Y0074284*
X0617561*
Y007423*
X0617669*
Y0074176*
X0617777*
Y0074121*
X0617831*
Y0074067*
X0617939*
Y0074013*
X0618047*
Y0073959*
X0618155*
Y0073905*
X0618264*
Y0073851*
X0618372*
Y0073797*
X061848*
Y0073743*
X0618588*
Y0073689*
X0618696*
Y0073635*
X0618804*
Y0073581*
X0618912*
Y0073527*
X0619021*
Y0073473*
X0619129*
Y0073419*
X0619237*
Y0073365*
X0619345*
Y0073311*
X0619453*
Y0073256*
X0619615*
Y0073203*
X0619723*
Y0073148*
X0619831*
Y0073094*
X0619994*
Y007304*
X0620102*
Y0072986*
X0620264*
Y0072932*
X0620372*
Y0072878*
X0620534*
Y0072824*
X0620642*
Y007277*
X0620805*
Y0072716*
X0620967*
Y0072662*
X0621129*
Y0072608*
X0621237*
Y0072554*
X0621399*
Y00725*
X0621561*
Y0072446*
X0621778*
Y0072391*
X062194*
Y0072338*
X0622102*
Y0072283*
X0622318*
Y0072229*
X062248*
Y0072175*
X0622697*
Y0072121*
X0622913*
Y0072067*
X0623129*
Y0072013*
X0623345*
Y0071959*
X0623616*
Y0071905*
X0623832*
Y0071851*
X0624102*
Y0071797*
X0624427*
Y0071743*
X0624751*
Y0071689*
X062513*
Y0071635*
X0625508*
Y0071581*
X0626049*
Y0071526*
X0626697*
Y0071473*
X0629292*
Y0071526*
X0629995*
Y0071581*
X0630482*
Y0071635*
X0630914*
Y0071689*
X0631293*
Y0071743*
X0631617*
Y0071797*
X0631887*
Y0071851*
X0632212*
Y0071905*
X0632428*
Y0071959*
X0632644*
Y0072013*
X0632914*
Y0072067*
X0633131*
Y0072121*
X0633347*
Y0072175*
X0633563*
Y0072229*
X0633725*
Y0072283*
X0633942*
Y0072338*
X0634104*
Y0072391*
X0634266*
Y0072446*
X0634428*
Y00725*
X063459*
Y0072554*
X0634753*
Y0072608*
X0634915*
Y0072662*
X0635077*
Y0072716*
X0635239*
Y007277*
X0635401*
Y0072824*
X0635509*
Y0072878*
X0635672*
Y0072932*
X063578*
Y0072986*
X0635942*
Y007304*
X063605*
Y0073094*
X0636212*
Y0073148*
X063632*
Y0073203*
X0636428*
Y0073256*
X0636591*
Y0073311*
X0636699*
Y0073365*
X0636807*
Y0073419*
X0636915*
Y0073473*
X0637023*
Y0073527*
X0637131*
Y0073581*
X0637239*
Y0073635*
X0637348*
Y0073689*
X0637456*
Y0073743*
X0637564*
Y0073797*
X0637672*
Y0073851*
X063778*
Y0073905*
X0637888*
Y0073959*
X0637996*
Y0074013*
X0638104*
Y0074067*
X0638158*
Y0074121*
X0638267*
Y0074176*
X0638375*
Y007423*
X0638483*
Y0074284*
X0638537*
Y0074338*
X0638645*
Y0074392*
X0638753*
Y0074446*
X0638807*
Y00745*
X0638915*
Y0074554*
X0639023*
Y0074608*
X0639078*
Y0074662*
X0639186*
Y0074716*
X063924*
Y007477*
X0639348*
Y0074824*
X0639456*
Y0074878*
X063951*
Y0074932*
X0639618*
Y0074986*
X0639672*
Y0075041*
X063978*
Y0075095*
X0639834*
Y0075149*
X0639888*
Y0075203*
X0639996*
Y0075257*
X0640051*
Y0075311*
X0640159*
Y0075365*
X0640213*
Y0075419*
X0640321*
Y0075473*
X0640375*
Y0075527*
X0640429*
Y0075581*
X0640537*
Y0075635*
X0640591*
Y0075689*
X0640645*
Y0075743*
X0640753*
Y0075797*
X0640807*
Y0075852*
X0640862*
Y0075906*
X0640916*
Y007596*
X0641024*
Y0076014*
X0641078*
Y0076068*
X0641132*
Y0076122*
X0641186*
Y0076176*
X0641294*
Y007623*
X0641348*
Y0076284*
X0641402*
Y0076338*
X0641456*
Y0076392*
X064151*
Y0076446*
X0641618*
Y00765*
X0641673*
Y0076554*
X0641726*
Y0076608*
X0641781*
Y0076662*
X0641835*
Y0076717*
X0641889*
Y0076771*
X0641943*
Y0076825*
X0642051*
Y0076879*
X0642105*
Y0076933*
X0642159*
Y0076987*
X0642213*
Y0077041*
X0642267*
Y0077095*
X0642321*
Y0077149*
X0642375*
Y0077203*
X0642429*
Y0077257*
X0642483*
Y0077311*
X0642537*
Y0077365*
X0642591*
Y0077419*
X0642646*
Y0077473*
X06427*
Y0077527*
X0642754*
Y0077582*
X0642808*
Y0077636*
X0642862*
Y007769*
X0642916*
Y0077744*
X064297*
Y0077798*
X0643024*
Y0077852*
X0643078*
Y0077906*
X0643132*
Y007796*
X0643186*
Y0078014*
X064324*
Y0078068*
X0643294*
Y0078122*
X0643348*
Y0078176*
X0643402*
Y007823*
X0643457*
Y0078284*
X0643511*
Y0078338*
X0643565*
Y0078392*
Y0078447*
X0643619*
Y00785*
X0643673*
Y0078555*
X0643727*
Y0078609*
X0643781*
Y0078663*
X0643835*
Y0078717*
X0643889*
Y0078771*
X0643943*
Y0078825*
Y0078879*
X0643997*
Y0078933*
X0643132*
Y0078879*
X0643078*
Y0078825*
X0643024*
Y0078771*
Y0078717*
X064297*
Y0078663*
X0642916*
Y0078609*
X0642862*
Y0078555*
X0642808*
Y00785*
X0642754*
Y0078447*
X06427*
Y0078392*
X0642646*
Y0078338*
X0642591*
Y0078284*
X0642537*
Y007823*
X0642483*
Y0078176*
X0642429*
Y0078122*
X0642375*
Y0078068*
X0642321*
Y0078014*
X0642267*
Y007796*
X0642213*
Y0077906*
X0642159*
Y0077852*
X0642105*
Y0077798*
X0642051*
Y0077744*
X0641997*
Y007769*
X0641943*
Y0077636*
X0641889*
Y0077582*
X0641835*
Y0077527*
X0641781*
Y0077473*
X0641726*
Y0077419*
X0641673*
Y0077365*
X0641564*
Y0077311*
X064151*
Y0077257*
X0641456*
Y0077203*
X0641402*
Y0077149*
X0641348*
Y0077095*
X0641294*
Y0077041*
X064124*
Y0076987*
X0641132*
Y0076933*
X0641078*
Y0076879*
X0641024*
Y0076825*
X064097*
Y0076771*
X0640916*
Y0076717*
X0640807*
Y0076662*
X0640753*
Y0076608*
X0640699*
Y0076554*
X0640645*
Y00765*
X0640537*
Y0076446*
X0640483*
Y0076392*
X0640429*
Y0076338*
X0640375*
Y0076284*
X0640267*
Y007623*
X0640213*
Y0076176*
X0640159*
Y0076122*
X0640051*
Y0076068*
X0639996*
Y0076014*
X0639943*
Y007596*
X0639834*
Y0075906*
X063978*
Y0075852*
X0639672*
Y0075797*
X0639618*
Y0075743*
X0639564*
Y0075689*
X0639456*
Y0075635*
X0639402*
Y0075581*
X0639294*
Y0075527*
X063924*
Y0075473*
X0639131*
Y0075419*
X0639078*
Y0075365*
X0638969*
Y0075311*
X0638915*
Y0075257*
X0638807*
Y0075203*
X0638699*
Y0075149*
X0638645*
Y0075095*
X0638537*
Y0075041*
X0638429*
Y0074986*
X0638375*
Y0074932*
X0638267*
Y0074878*
X0638158*
Y0074824*
X0638104*
Y007477*
X0637996*
Y0074716*
X0637888*
Y0074662*
X063778*
Y0074608*
X0637726*
Y0074554*
X0637618*
Y00745*
X063751*
Y0074446*
X0637402*
Y0074392*
X0637293*
Y0074338*
X0637185*
Y0074284*
X0637077*
Y007423*
X0636969*
Y0074176*
X0636861*
Y0074121*
X0636753*
Y0074067*
X0636645*
Y0074013*
X0636537*
Y0073959*
X0636428*
Y0073905*
X063632*
Y0073851*
X0636158*
Y0073797*
X063605*
Y0073743*
X0635888*
Y0073689*
X063578*
Y0073635*
X0635672*
Y0073581*
X0635509*
Y0073527*
X0635401*
Y0073473*
X0635239*
Y0073419*
X0635077*
Y0073365*
X0634969*
Y0073311*
X0634807*
Y0073256*
X0634644*
Y0073203*
X0634482*
Y0073148*
X063432*
Y0073094*
X0634158*
Y007304*
X0633996*
Y0072986*
X0633834*
Y0072932*
X0633617*
Y0072878*
X0633455*
Y0072824*
X0633239*
Y007277*
X0633022*
Y0072716*
X0632806*
Y0072662*
X063259*
Y0072608*
X063232*
Y0072554*
X0632103*
Y00725*
X0631833*
Y0072446*
X0631509*
Y0072391*
X0631184*
Y0072338*
X0630806*
Y0072283*
X0630482*
Y0072229*
X0629833*
Y0072175*
X0629238*
Y0072121*
X0629184*
Y0072175*
X0629076*
Y0072121*
X0626968*
Y0072175*
X0626157*
Y0072229*
X062567*
Y0072283*
X0625238*
Y0072338*
X0624859*
Y0072391*
X0624535*
Y0072446*
X062421*
Y00725*
X062394*
Y0072554*
X062367*
Y0072608*
X0623454*
Y0072662*
X0623237*
Y0072716*
X0623021*
Y007277*
X0622805*
Y0072824*
X0622589*
Y0072878*
X0622426*
Y0072932*
X062221*
Y0072986*
X0622048*
Y007304*
X0621886*
Y0073094*
X0621724*
Y0073148*
X0621561*
Y0073203*
X0621399*
Y0073256*
X0621237*
Y0073311*
X0621075*
Y0073365*
X0620913*
Y0073419*
X0620805*
Y0073473*
X0620642*
Y0073527*
X0620534*
Y0073581*
X0620372*
Y0073635*
X0620264*
Y0073689*
X0620102*
Y0073743*
X0619994*
Y0073797*
X0619885*
Y0073851*
X0619777*
Y0073905*
X0619615*
Y0073959*
X0619507*
Y0074013*
X0619399*
Y0074067*
X0619291*
Y0074121*
X0619183*
Y0074176*
X0619074*
Y007423*
X0618966*
Y0074284*
X0618858*
Y0074338*
X061875*
Y0074392*
X0618642*
Y0074446*
X0618534*
Y00745*
X0618426*
Y0074554*
X0618318*
Y0074608*
X0618264*
Y0074662*
X0618155*
Y0074716*
X0618047*
Y007477*
X0617939*
Y0074824*
X0617831*
Y0074878*
X0617777*
Y0074932*
X0617669*
Y0074986*
X0617561*
Y0075041*
X0617507*
Y0075095*
X0617399*
Y0075149*
X0617345*
Y0075203*
X0617236*
Y0075257*
X0617128*
Y0075311*
X0617074*
Y0075365*
X0616966*
Y0075419*
X0616912*
Y0075473*
X0616804*
Y0075527*
X061675*
Y0075581*
X0616642*
Y0075635*
X0616588*
Y0075689*
X061648*
Y0075743*
X0616426*
Y0075797*
X0616317*
Y0075852*
X0616263*
Y0075906*
X0616209*
Y007596*
X0616101*
Y0076014*
X0616047*
Y0076068*
X0615993*
Y0076122*
X0615885*
Y0076176*
X0615831*
Y007623*
X0615777*
Y0076284*
X0615669*
Y0076338*
X0615615*
Y0076392*
X061556*
Y0076446*
X0615452*
Y00765*
X0615398*
Y0076554*
X0615344*
Y0076608*
X061529*
Y0076662*
X0615182*
Y0076717*
X0615128*
Y0076771*
X0615074*
Y0076825*
X061502*
Y0076879*
X0614966*
Y0076933*
X0614858*
Y0076987*
X0614804*
Y0077041*
X061475*
Y0077095*
X0614696*
Y0077149*
X0614641*
Y0077203*
X0614587*
Y0077257*
X0614533*
Y0077311*
X0614425*
Y0077365*
X0614371*
Y0077419*
X0614317*
Y0077473*
X0614263*
Y0077527*
X0614209*
Y0077582*
X0614155*
Y0077636*
X0614101*
Y007769*
X0614047*
Y0077744*
X0613993*
Y0077798*
X0613939*
Y0077852*
X0613885*
Y0077906*
X0613831*
Y007796*
X0613776*
Y0078014*
X0613722*
Y0078068*
X0613668*
Y0078122*
X0613614*
Y0078176*
X061356*
Y007823*
X0613506*
Y0078284*
X0613452*
Y0078338*
X0613398*
Y0078392*
X0613344*
Y0078447*
X061329*
Y00785*
X0613236*
Y0078555*
X0613182*
Y0078609*
X0613128*
Y0078663*
X0613074*
Y0078717*
X061302*
Y0078771*
X0612965*
Y0078825*
Y0078879*
X0612912*
Y0078933*
X0612857*
Y0078987*
X0612803*
Y0079041*
X0612749*
Y0079095*
X0612695*
Y0079149*
X0612641*
Y0079203*
X0612587*
Y0079257*
Y0079312*
X0612533*
Y0079365*
X0612479*
Y007942*
X0612425*
Y0079474*
X0612371*
Y0079528*
X0612317*
Y0079582*
Y0079636*
X0612263*
Y007969*
X0612209*
Y0079744*
X0612155*
Y0079798*
X0612101*
Y0079852*
Y0079906*
X0612046*
Y007996*
X0611992*
Y0080014*
X0611938*
Y0080068*
Y0080122*
X0611884*
Y0080177*
X061183*
Y008023*
X0611776*
Y0080285*
Y0080339*
X0611722*
Y0080393*
X0611668*
Y0080447*
X0611614*
Y0080501*
Y0080555*
X061156*
Y0080609*
X0611506*
Y0080663*
X0611452*
Y0080717*
Y0080771*
X0611398*
Y0080825*
X0611344*
Y0080879*
Y0080933*
X061129*
Y0080987*
X0611236*
Y0081042*
Y0081095*
X0611181*
Y008115*
X0611127*
Y0081204*
Y0081258*
X0611073*
Y0081312*
X0611019*
Y0081366*
Y008142*
X0610965*
Y0081474*
X0610911*
Y0081528*
Y0081582*
X0610857*
Y0081636*
Y008169*
X0610803*
Y0081744*
X0610749*
Y0081798*
Y0081852*
X0610695*
Y0081906*
X0610641*
Y008196*
Y0082015*
X0610587*
Y0082069*
Y0082123*
X0610533*
Y0082177*
Y0082231*
X0610479*
Y0082285*
X0610425*
Y0082339*
Y0082393*
X0610371*
Y0082447*
Y0082501*
X0610317*
Y0082555*
Y0082609*
X0610262*
Y0082663*
X0610208*
Y0082717*
Y0082771*
X0610154*
Y0082825*
Y008288*
X06101*
Y0082934*
Y0082988*
X0610046*
Y0083042*
Y0083096*
X0609992*
Y008315*
Y0083204*
X0609938*
Y0083258*
Y0083312*
X0609884*
Y0083366*
Y008342*
X060983*
Y0083474*
Y0083528*
X0609776*
Y0083582*
Y0083636*
X0609722*
Y0083691*
Y0083745*
X0609668*
Y0083799*
Y0083853*
X0609614*
Y0083907*
Y0083961*
X060956*
Y0084015*
Y0084069*
Y0084123*
X0609506*
Y0084177*
Y0084231*
X0609451*
Y0084285*
Y0084339*
X0609397*
Y0084393*
Y0084447*
Y0084501*
X0609343*
Y0084556*
Y008461*
X0609289*
Y0084664*
Y0084718*
X0609235*
Y0084772*
Y0084826*
Y008488*
X0609181*
Y0084934*
Y0084988*
X0609127*
Y0085042*
Y0085096*
Y008515*
X0609073*
Y0085204*
Y0085258*
Y0085312*
X0609019*
Y0085366*
Y0085421*
X0608965*
Y0085474*
Y0085529*
Y0085583*
X0608911*
Y0085637*
Y0085691*
Y0085745*
X0608857*
Y0085799*
Y0085853*
Y0085907*
X0608803*
Y0085961*
Y0086015*
Y0086069*
X0608749*
Y0086123*
Y0086177*
Y0086231*
X0608695*
Y0086286*
Y0086339*
Y0086394*
X0608641*
Y0086448*
Y0086502*
Y0086556*
X0608587*
Y008661*
Y0086664*
Y0086718*
Y0086772*
X0608532*
Y0086826*
Y008688*
Y0086934*
X0608478*
Y0086988*
Y0087042*
Y0087096*
Y0087151*
X0608424*
Y0087204*
Y0087259*
Y0087313*
Y0087367*
X060837*
Y0087421*
Y0087475*
Y0087529*
Y0087583*
X0608316*
Y0087637*
Y0087691*
Y0087745*
Y0087799*
X0608262*
Y0087853*
Y0087907*
Y0087961*
Y0088016*
Y0088069*
X0608208*
Y0088124*
Y0088178*
Y0088232*
Y0088286*
Y008834*
X0608154*
Y0088394*
Y0088448*
Y0088502*
Y0088556*
Y008861*
X06081*
Y0088664*
Y0088718*
Y0088772*
Y0088826*
Y008888*
X0608046*
Y0088934*
Y0088989*
Y0089043*
Y0089097*
Y0089151*
Y0089205*
X0607992*
Y0089259*
Y0089313*
Y0089367*
Y0089421*
Y0089475*
Y0089529*
Y0089583*
X0607938*
Y0089637*
Y0089691*
Y0089745*
Y0089799*
Y0089854*
Y0089908*
Y0089962*
Y0090016*
X0607884*
Y009007*
Y0090124*
Y0090178*
Y0090232*
Y0090286*
Y009034*
Y0090394*
Y0090448*
Y0090502*
Y0090556*
X060783*
Y009061*
Y0090664*
Y0090719*
Y0090773*
Y0090827*
Y0090881*
Y0090935*
Y0090989*
Y0091043*
Y0091097*
Y0091151*
Y0091205*
Y0091259*
Y0091313*
Y0091367*
Y0091421*
X0607776*
Y0091475*
Y009153*
Y0091584*
Y0091638*
Y0091692*
Y0091746*
G37*
G36*
X0437992Y0265748D02*
X0392717D01*
Y0242126*
X0437992*
Y0265748*
G37*
G36*
X055945Y0255145D02*
X055801D01*
X0556598Y0254864*
X0555267Y0254313*
X055407Y0253513*
X0553052Y0252495*
X0552252Y0251298*
X05517Y0249967*
X055142Y0248555*
Y0247835*
Y0247115*
X05517Y0245702*
X0552252Y0244372*
X0553052Y0243174*
X055407Y0242156*
X0555267Y0241356*
X0556598Y0240805*
X055801Y0240524*
X055945*
X0560863Y0240805*
X0562193Y0241356*
X056339Y0242156*
X0564409Y0243174*
X0565209Y0244372*
X056576Y0245702*
X0566041Y0247115*
Y0247835*
Y0248555*
X056576Y0249967*
X0565209Y0251298*
X0564409Y0252495*
X056339Y0253513*
X0562193Y0254313*
X0560863Y0254864*
X055945Y0255145*
G37*
G36*
Y0175224D02*
X055801D01*
X0556598Y0174943*
X0555267Y0174392*
X055407Y0173592*
X0553052Y0172574*
X0552252Y0171376*
X05517Y0170046*
X055142Y0168633*
Y0167913*
Y0167193*
X05517Y0165781*
X0552252Y0164451*
X0553052Y0163253*
X055407Y0162235*
X0555267Y0161435*
X0556598Y0160884*
X055801Y0160603*
X055945*
X0560863Y0160884*
X0562193Y0161435*
X056339Y0162235*
X0564409Y0163253*
X0565209Y0164451*
X056576Y0165781*
X0566041Y0167193*
Y0167913*
Y0168633*
X056576Y0170046*
X0565209Y0171376*
X0564409Y0172574*
X056339Y0173592*
X0562193Y0174392*
X0560863Y0174943*
X055945Y0175224*
G37*
G36*
X041437Y0187008D02*
X0384842D01*
Y017864*
X0384771Y0178468*
Y0177831*
X0384842Y0177659*
Y0163955*
X0384772Y0163785*
Y0163148*
X0384842Y0162977*
Y0161235*
X0384833Y0161211*
Y0160574*
X0384842Y016055*
Y0147638*
X041437*
Y0187008*
G37*
G36*
X055945Y0095303D02*
X055801D01*
X0556598Y0095022*
X0555267Y0094471*
X055407Y0093671*
X0553052Y0092652*
X0552252Y0091455*
X05517Y0090125*
X055142Y0088712*
Y0087992*
Y0087272*
X05517Y008586*
X0552252Y0084529*
X0553052Y0083332*
X055407Y0082314*
X0555267Y0081514*
X0556598Y0080962*
X055801Y0080682*
X055945*
X0560863Y0080962*
X0562193Y0081514*
X056339Y0082314*
X0564409Y0083332*
X0565209Y0084529*
X056576Y008586*
X0566041Y0087272*
Y0087992*
Y0088712*
X056576Y0090125*
X0565209Y0091455*
X0564409Y0092652*
X056339Y0093671*
X0562193Y0094471*
X0560863Y0095022*
X055945Y0095303*
G37*
G36*
X0399608D02*
X0398168D01*
X0396755Y0095022*
X0395425Y0094471*
X0394227Y0093671*
X0393209Y0092652*
X0392409Y0091455*
X0391858Y0090125*
X0391577Y0088712*
Y0087992*
Y0087272*
X0391858Y008586*
X0392409Y0084529*
X0393209Y0083332*
X0394227Y0082314*
X0395425Y0081514*
X0396755Y0080962*
X0398168Y0080682*
X0399608*
X040102Y0080962*
X0402351Y0081514*
X0403548Y0082314*
X0404566Y0083332*
X0405366Y0084529*
X0405918Y008586*
X0406198Y0087272*
Y0087992*
Y0088712*
X0405918Y0090125*
X0405366Y0091455*
X0404566Y0092652*
X0403548Y0093671*
X0402351Y0094471*
X040102Y0095022*
X0399608Y0095303*
G37*
%LNtimecard-dc-beta-v1-3*%
%LPD*%
G36*
X0652431Y008888D02*
X0652539D01*
Y0088826*
Y0088772*
Y0088718*
Y0088664*
Y008861*
Y0088556*
Y0088502*
Y0088448*
Y0088394*
Y008834*
Y0088286*
Y0088232*
Y0088178*
Y0088124*
Y0088069*
Y0088016*
Y0087961*
Y0087907*
Y0087853*
Y0087799*
Y0087745*
Y0087691*
Y0087637*
Y0087583*
Y0087529*
Y0087475*
Y0087421*
Y0087367*
Y0087313*
Y0087259*
Y0087204*
Y0087151*
Y0087096*
Y0087042*
Y0086988*
Y0086934*
Y008688*
Y0086826*
Y0086772*
Y0086718*
Y0086664*
Y008661*
Y0086556*
Y0086502*
Y0086448*
Y0086394*
Y0086339*
Y0086286*
Y0086231*
Y0086177*
Y0086123*
Y0086069*
Y0086015*
Y0085961*
Y0085907*
Y0085853*
Y0085799*
Y0085745*
Y0085691*
Y0085637*
Y0085583*
Y0085529*
Y0085474*
Y0085421*
Y0085366*
Y0085312*
Y0085258*
Y0085204*
Y008515*
Y0085096*
Y0085042*
Y0084988*
Y0084934*
Y008488*
Y0084826*
Y0084772*
Y0084718*
Y0084664*
Y008461*
Y0084556*
Y0084501*
Y0084447*
Y0084393*
Y0084339*
Y0084285*
Y0084231*
Y0084177*
Y0084123*
Y0084069*
Y0084015*
Y0083961*
Y0083907*
Y0083853*
Y0083799*
Y0083745*
Y0083691*
Y0083636*
Y0083582*
Y0083528*
Y0083474*
Y008342*
Y0083366*
Y0083312*
Y0083258*
Y0083204*
Y008315*
Y0083096*
Y0083042*
Y0082988*
Y0082934*
Y008288*
X0648592*
Y0082934*
Y0082988*
Y0083042*
Y0083096*
Y008315*
Y0083204*
Y0083258*
Y0083312*
Y0083366*
Y008342*
Y0083474*
Y0083528*
Y0083582*
Y0083636*
Y0083691*
Y0083745*
Y0083799*
Y0083853*
Y0083907*
Y0083961*
Y0084015*
Y0084069*
Y0084123*
Y0084177*
Y0084231*
Y0084285*
Y0084339*
Y0084393*
Y0084447*
Y0084501*
Y0084556*
Y008461*
Y0084664*
Y0084718*
Y0084772*
Y0084826*
Y008488*
Y0084934*
Y0084988*
Y0085042*
Y0085096*
Y008515*
Y0085204*
Y0085258*
Y0085312*
Y0085366*
Y0085421*
Y0085474*
Y0085529*
Y0085583*
Y0085637*
Y0085691*
Y0085745*
Y0085799*
Y0085853*
Y0085907*
Y0085961*
Y0086015*
Y0086069*
Y0086123*
Y0086177*
Y0086231*
Y0086286*
Y0086339*
Y0086394*
Y0086448*
Y0086502*
Y0086556*
Y008661*
Y0086664*
Y0086718*
Y0086772*
Y0086826*
Y008688*
Y0086934*
Y0086988*
Y0087042*
Y0087096*
Y0087151*
Y0087204*
Y0087259*
Y0087313*
Y0087367*
Y0087421*
Y0087475*
Y0087529*
Y0087583*
Y0087637*
Y0087691*
Y0087745*
Y0087799*
Y0087853*
Y0087907*
Y0087961*
Y0088016*
Y0088069*
Y0088124*
Y0088178*
Y0088232*
Y0088286*
Y008834*
Y0088394*
Y0088448*
Y0088502*
Y0088556*
Y008861*
Y0088664*
Y0088718*
Y0088772*
Y0088826*
Y008888*
X0648646*
Y0088934*
X0648701*
Y008888*
X0652214*
Y0088934*
X0652269*
Y008888*
X0652377*
Y0088934*
X0652431*
Y008888*
G37*
G36*
X0641024Y0088989D02*
Y0088934D01*
Y008888*
Y0088826*
Y0088772*
Y0088718*
Y0088664*
Y008861*
Y0088556*
Y0088502*
Y0088448*
Y0088394*
Y008834*
Y0088286*
Y0088232*
Y0088178*
Y0088124*
Y0088069*
Y0088016*
Y0087961*
Y0087907*
Y0087853*
Y0087799*
Y0087745*
Y0087691*
Y0087637*
Y0087583*
Y0087529*
Y0087475*
Y0087421*
Y0087367*
Y0087313*
Y0087259*
Y0087204*
Y0087151*
Y0087096*
Y0087042*
Y0086988*
Y0086934*
Y008688*
Y0086826*
Y0086772*
Y0086718*
Y0086664*
Y008661*
Y0086556*
Y0086502*
Y0086448*
Y0086394*
Y0086339*
Y0086286*
Y0086231*
Y0086177*
X0636969*
Y0086231*
Y0086286*
Y0086339*
Y0086394*
Y0086448*
Y0086502*
Y0086556*
Y008661*
Y0086664*
Y0086718*
Y0086772*
Y0086826*
Y008688*
Y0086934*
Y0086988*
Y0087042*
Y0087096*
Y0087151*
Y0087204*
Y0087259*
Y0087313*
Y0087367*
Y0087421*
Y0087475*
Y0087529*
Y0087583*
Y0087637*
Y0087691*
Y0087745*
Y0087799*
Y0087853*
Y0087907*
Y0087961*
Y0088016*
Y0088069*
Y0088124*
Y0088178*
Y0088232*
Y0088286*
Y008834*
Y0088394*
Y0088448*
Y0088502*
Y0088556*
Y008861*
Y0088664*
Y0088718*
Y0088772*
Y0088826*
Y008888*
Y0088934*
Y0088989*
Y0089043*
X0641024*
Y0088989*
G37*
G54D13*
X0181368Y0357677D02*
X0181565Y035748D01*
X017687Y0357677D02*
X0181368D01*
X0181565Y035748D02*
X0181727D01*
X0167474Y0198896D02*
X0167484Y0198906D01*
X0161711Y0198896D02*
X0167474D01*
X0164581Y0149706D02*
X0167084D01*
X0171962Y0149684D02*
X0177655D01*
X0171884Y0149606D02*
X0171962Y0149684D01*
X0167084Y0149706D02*
X0167184Y0149606D01*
X0659449Y0177559D02*
X0664244D01*
X0659449Y0172047D02*
X0664232D01*
X0172194Y0198896D02*
X0177655D01*
X0172232Y0189054D02*
X0177655D01*
X0171889Y0179211D02*
X0177655D01*
X0171504Y0159526D02*
X0177655D01*
X0171749Y0139841D02*
X0177655D01*
X0637008Y0267323D02*
X0645182D01*
X0635945D02*
X0637008D01*
Y026063D02*
X0645276D01*
X0635945D02*
X0637008D01*
Y0274016D02*
X0645084D01*
X0635945D02*
X0637008D01*
Y0253543D02*
X0645084D01*
X0635945D02*
X0637008D01*
X026063Y010629D02*
Y0110073D01*
X0261024Y0110468D02*
Y011063D01*
X026063Y0110073D02*
X0261024Y0110468D01*
X0172184Y0168571D02*
X0172347D01*
X0173053Y0169277*
X0175066*
X0166922Y0168571D02*
X0167084D01*
X0166224Y0169269D02*
X0166922Y0168571D01*
X0164224Y0169269D02*
X0166224D01*
X0292921Y0330806D02*
Y0330913D01*
X0636775Y0246263D02*
X0645084D01*
X0636575Y0246063D02*
X0636775Y0246263D01*
X0662766Y0152931D02*
X0662941Y0153106D01*
X065878Y0152931D02*
X0662766D01*
X0664232Y0172047D02*
X0664291Y0172106D01*
X0172184Y0198906D02*
X0172194Y0198896D01*
X0260668Y0087887D02*
Y009319D01*
X0171484Y0159506D02*
X0171504Y0159526D01*
X0161719Y0149692D02*
X0164567D01*
X0260668Y009319D02*
X0260884Y0093406D01*
X0161716Y0179206D02*
X0167184D01*
X0172184Y0189006D02*
X0172232Y0189054D01*
X0161711D02*
X0167532D01*
X0161711Y0179211D02*
X0161716Y0179206D01*
X0164567Y0149692D02*
X0164581Y0149706D01*
X0161711Y0159526D02*
X0167064D01*
X0167084Y0159506*
X0161711Y0139841D02*
X0167119D01*
X0171884Y0179206D02*
X0171889Y0179211D01*
X0171684Y0139906D02*
X0171749Y0139841D01*
X0167532Y0189054D02*
X0167584Y0189106D01*
X0161711Y0149684D02*
X0161719Y0149692D01*
X0167119Y0139841D02*
X0167184Y0139906D01*
X0662884Y0137206D02*
X0662941Y0137263D01*
Y0142106*
X0352035Y0072606D02*
X0355409D01*
X0349853Y0070424D02*
X0352035Y0072606D01*
X0349853Y0068206D02*
Y0070424D01*
X0355409Y0072349D02*
Y0072606D01*
X0673661Y018189D02*
Y0182172D01*
X0672744Y018309D02*
X0673661Y0182172D01*
X0669478Y018309D02*
X0672744D01*
X066374Y0188106D02*
X0669984D01*
X0690634Y0209606D02*
X0694884D01*
X0694984Y0209506*
X0665028Y0217606D02*
X0665984Y021665D01*
X0660784Y0217606D02*
X0665028D01*
X0633484Y0211063D02*
X0639541D01*
X0639584Y0211106*
X0604884Y0217106D02*
X0609335D01*
X0600394Y0238937D02*
Y0243021D01*
X0627484Y0239106D02*
X0635228D01*
G54D18*
X0264605Y0097993D02*
D01*
X0264605Y0097968*
X0264608Y0097943*
X0264612Y0097919*
X0264618Y0097895*
X0264626Y0097871*
X0264635Y0097848*
X0264646Y0097826*
X0264658Y0097804*
X0264672Y0097784*
X0264688Y0097764*
X0264704Y0097746*
X0264722Y0097729*
X0264741Y0097713*
X0264761Y0097698*
X0264782Y0097685*
X0264804Y0097673*
X0264827Y0097663*
X026485Y0097655*
X0264874Y0097648*
X0264898Y0097643*
X0264922Y0097639*
X0264947Y0097638*
X0264961Y0097638*
X0241339Y0027953D02*
D01*
X0240923Y0027506*
X0240539Y0027033*
X0240189Y0026533*
X0239875Y002601*
X0239598Y0025467*
X023936Y0024906*
X0239161Y0024329*
X0239003Y002374*
X0238887Y0023141*
X0238813Y0022536*
X0238781Y0021927*
X0238779Y0021775*
X0244488Y0027953D02*
D01*
X02442Y0027644*
X0243934Y0027316*
X0243692Y002697*
X0243474Y0026608*
X0243283Y0026232*
X0243118Y0025843*
X024298Y0025444*
X0242871Y0025036*
X024279Y0024622*
X0242739Y0024203*
X0242717Y0023781*
X0242717Y0023676*
X0270079Y0083071D02*
D01*
X0269951Y0082933*
X0269832Y0082787*
X0269725Y0082634*
X0269628Y0082473*
X0269543Y0082306*
X026947Y0082133*
X0269409Y0081956*
X026936Y0081774*
X0269324Y008159*
X0269301Y0081404*
X0269291Y0081216*
X0269291Y008117*
X0258465Y0026527D02*
D01*
X025846Y0026667*
X0258445Y0026807*
X025842Y0026946*
X0258386Y0027082*
X0258343Y0027216*
X025829Y0027346*
X0258229Y0027473*
X0258158Y0027595*
X0258079Y0027711*
X0257993Y0027822*
X0257899Y0027927*
X0257874Y0027953*
X0267927Y0082888D02*
D01*
X0267926Y0082887*
X0267926Y0082887*
X0267926Y0082887*
X0267926Y0082887*
X0267927Y0082887*
D01*
X02677Y0082644*
X0267492Y0082386*
X0267302Y0082114*
X0267131Y008183*
X026698Y0081534*
X0266851Y0081229*
X0266743Y0080915*
X0266657Y0080595*
X0266594Y0080269*
X0266554Y007994*
X0266536Y0079609*
X0266535Y0079528*
X0261024Y0025917D02*
D01*
X026103Y0025729*
X026105Y0025542*
X0261082Y0025358*
X0261128Y0025176*
X0261186Y0024997*
X0261256Y0024823*
X0261338Y0024655*
X0261432Y0024492*
X0261537Y0024337*
X0261652Y0024189*
X0261778Y0024049*
X0261811Y0024016*
X0262402Y002259D02*
D01*
X0262397Y002273*
X0262382Y002287*
X0262357Y0023009*
X0262323Y0023145*
X026228Y0023279*
X0262227Y0023409*
X0262166Y0023536*
X0262095Y0023658*
X0262016Y0023774*
X026193Y0023885*
X0261836Y002399*
X0261811Y0024016*
X0282322Y0080384D02*
D01*
X0282324Y0080299*
X0282333Y0080215*
X0282348Y0080132*
X0282368Y0080049*
X0282395Y0079969*
X0282426Y0079891*
X0282463Y0079815*
X0282506Y0079741*
X0282553Y0079671*
X0282605Y0079604*
X0282662Y0079542*
X0282677Y0079528*
X0274871Y0028214D02*
D01*
X0274854Y0028183*
X027484Y0028151*
X0274836Y0028141*
X0274688Y0027827D02*
D01*
X0274709Y0027854*
X0274728Y0027883*
X0274746Y0027913*
X0274761Y0027945*
X027477Y0027968*
X0274686Y0027825D02*
D01*
X0274599Y0027714*
X027452Y0027597*
X0274449Y0027475*
X0274387Y0027349*
X0274335Y0027218*
X0274291Y0027085*
X0274257Y0026948*
X0274232Y002681*
X0274217Y002667*
X0274212Y0026529*
X0274213Y0026527*
X027815Y0027478D02*
D01*
X0278148Y0027524*
X0278143Y0027571*
X0278135Y0027617*
X0278123Y0027663*
X0278109Y0027707*
X0278091Y0027751*
X0278071Y0027793*
X0278047Y0027834*
X0278021Y0027872*
X0277992Y0027909*
X0277961Y0027944*
X0277953Y0027953*
X0290551D02*
D01*
X029055Y0027952*
X029055Y0027952*
X0290549Y0027951*
X0290549Y0027951*
X0290549Y002795*
Y0027951*
D01*
X0290453Y0027847*
X0290364Y0027738*
X0290284Y0027622*
X0290211Y0027502*
X0290148Y0027376*
X0290093Y0027247*
X0290047Y0027113*
X0290011Y0026977*
X0289984Y0026839*
X0289967Y0026699*
X028996Y0026559*
X0289961Y0026527*
X0276416Y0097993D02*
D01*
X0276416Y0097968*
X0276419Y0097943*
X0276423Y0097919*
X0276429Y0097895*
X0276437Y0097871*
X0276446Y0097848*
X0276457Y0097826*
X0276469Y0097804*
X0276483Y0097784*
X0276499Y0097764*
X0276515Y0097746*
X0276533Y0097729*
X0276552Y0097713*
X0276572Y0097698*
X0276593Y0097685*
X0276615Y0097673*
X0276638Y0097663*
X0276661Y0097655*
X0276685Y0097648*
X0276709Y0097643*
X0276733Y0097639*
X0276758Y0097638*
X0276772Y0097638*
X0293898Y0027478D02*
D01*
X0293896Y0027524*
X0293891Y0027571*
X0293883Y0027617*
X0293871Y0027663*
X0293857Y0027707*
X0293839Y0027751*
X0293819Y0027793*
X0293795Y0027834*
X0293769Y0027872*
X029374Y0027909*
X0293709Y0027944*
X0293701Y0027953*
X0261811Y0082677D02*
D01*
X0261945Y0082821*
X0262069Y0082974*
X0262182Y0083135*
X0262283Y0083304*
X0262373Y0083479*
X0262449Y008366*
X0262514Y0083847*
X0262565Y0084037*
X0262602Y008423*
X0262626Y0084426*
X0262636Y0084622*
X0262637Y0084672*
X0260678Y0081544D02*
D01*
X0260542Y0081398*
X0260417Y0081243*
X0260302Y008108*
X02602Y008091*
X026011Y0080732*
X0260032Y0080549*
X0259967Y0080361*
X0259916Y0080169*
X0259878Y0079974*
X0259853Y0079776*
X0259843Y0079577*
X0259842Y0079528*
X0262992Y008189D02*
D01*
X0263254Y0082171*
X0263496Y0082469*
X0263716Y0082784*
X0263914Y0083114*
X0264088Y0083456*
X0264239Y008381*
X0264364Y0084173*
X0264463Y0084545*
X0264537Y0084922*
X0264583Y0085304*
X0264604Y0085687*
X0264605Y0085784*
X0262992Y008189D02*
D01*
X0262928Y0081821*
X0262869Y0081748*
X0262815Y0081671*
X0262766Y0081591*
X0262724Y0081507*
X0262687Y0081421*
X0262657Y0081332*
X0262632Y0081242*
X0262615Y008115*
X0262603Y0081057*
X0262598Y0080963*
X0262598Y0080939*
X0270511Y0097993D02*
D01*
X0270511Y0097968*
X0270514Y0097943*
X0270518Y0097919*
X0270524Y0097895*
X0270532Y0097871*
X0270541Y0097848*
X0270552Y0097826*
X0270564Y0097804*
X0270578Y0097784*
X0270594Y0097764*
X027061Y0097746*
X0270628Y0097729*
X0270647Y0097713*
X0270667Y0097698*
X0270688Y0097685*
X027071Y0097673*
X0270733Y0097663*
X0270756Y0097655*
X027078Y0097648*
X0270804Y0097643*
X0270828Y0097639*
X0270853Y0097638*
X0270866Y0097638*
X0274028Y0081902D02*
D01*
X0273898Y0081762*
X0273778Y0081614*
X0273668Y0081458*
X027357Y0081295*
X0273484Y0081125*
X0273409Y008095*
X0273347Y008077*
X0273298Y0080585*
X0273262Y0080398*
X0273238Y0080209*
X0273228Y0080019*
X0273228Y0079972*
X0288227Y0082287D02*
D01*
X0288236Y0082014*
X0288264Y0081743*
X0288312Y0081475*
X0288378Y0081211*
X0288462Y0080952*
X0288564Y0080699*
X0288683Y0080455*
X0288819Y0080219*
X0288972Y0079993*
X0289139Y0079778*
X0289322Y0079576*
X028937Y0079528*
X0282322Y0097993D02*
D01*
X0282322Y0097968*
X0282325Y0097943*
X0282329Y0097919*
X0282335Y0097895*
X0282343Y0097871*
X0282352Y0097848*
X0282363Y0097826*
X0282375Y0097804*
X0282389Y0097784*
X0282405Y0097764*
X0282421Y0097746*
X0282439Y0097729*
X0282458Y0097713*
X0282478Y0097698*
X0282499Y0097685*
X0282521Y0097673*
X0282544Y0097663*
X0282567Y0097655*
X0282591Y0097648*
X0282615Y0097643*
X0282639Y0097639*
X0282664Y0097638*
X0282677Y0097638*
X0286221Y0079528D02*
D01*
X0286227Y0079534*
X0286233Y0079541*
X0286238Y0079549*
X0286243Y0079557*
X0286247Y0079565*
X0286251Y0079574*
X0286254Y0079583*
X0286256Y0079592*
X0286258Y0079601*
X0286259Y007961*
X0286259Y0079619*
X0286259Y0079621*
X0270079Y0083071D02*
D01*
X0270149Y0083146*
X0270214Y0083226*
X0270273Y008331*
X0270326Y0083399*
X0270373Y0083491*
X0270413Y0083585*
X0270446Y0083683*
X0270473Y0083782*
X0270493Y0083884*
X0270505Y0083986*
X0270511Y0084089*
X0270511Y0084115*
X026811Y0097638D02*
D01*
X026814Y0097639*
X026817Y0097642*
X0268199Y0097647*
X0268229Y0097654*
X0268257Y0097664*
X0268285Y0097675*
X0268312Y0097688*
X0268338Y0097703*
X0268363Y009772*
X0268387Y0097739*
X026841Y0097759*
X0268431Y009778*
X026845Y0097804*
X0268468Y0097828*
X0268484Y0097854*
X0268498Y009788*
X026851Y0097908*
X026852Y0097936*
X0268529Y0097965*
X0268535Y0097994*
X0268539Y0098024*
X0268541Y0098054*
X0268542Y009807*
X0279921Y0097638D02*
D01*
X0279951Y0097639*
X0279981Y0097642*
X028001Y0097647*
X028004Y0097654*
X0280068Y0097664*
X0280096Y0097675*
X0280123Y0097688*
X0280149Y0097703*
X0280174Y009772*
X0280198Y0097739*
X0280221Y0097759*
X0280242Y009778*
X0280261Y0097804*
X0280279Y0097828*
X0280295Y0097854*
X0280309Y009788*
X0280321Y0097908*
X0280331Y0097936*
X028034Y0097965*
X0280346Y0097994*
X028035Y0098024*
X0280352Y0098054*
X0280353Y009807*
X0274016Y0097638D02*
D01*
X0274046Y0097639*
X0274076Y0097642*
X0274106Y0097647*
X0274135Y0097654*
X0274164Y0097664*
X0274192Y0097675*
X0274219Y0097688*
X0274245Y0097703*
X027427Y009772*
X0274294Y0097739*
X0274316Y0097759*
X0274337Y0097781*
X0274357Y0097804*
X0274374Y0097828*
X027439Y0097854*
X0274405Y0097881*
X0274417Y0097908*
X0274427Y0097937*
X0274436Y0097966*
X0274442Y0097995*
X0274446Y0098025*
X0274448Y0098055*
X0274448Y009807*
X0275984Y0079528D02*
D01*
X0276054Y0079603*
X0276119Y0079683*
X0276178Y0079767*
X0276231Y0079855*
X0276277Y0079947*
X0276318Y0080042*
X0276351Y0080139*
X0276378Y0080239*
X0276397Y008034*
X027641Y0080442*
X0276415Y0080545*
X0276416Y0080571*
X0279921Y0079528D02*
D01*
X0279991Y0079603*
X0280056Y0079683*
X0280115Y0079767*
X0280168Y0079855*
X0280214Y0079947*
X0280255Y0080042*
X0280288Y0080139*
X0280315Y0080239*
X0280334Y008034*
X0280347Y0080442*
X0280352Y0080545*
X0280353Y0080571*
X026811Y0083071D02*
D01*
X026818Y0083146*
X0268245Y0083226*
X0268304Y008331*
X0268357Y0083398*
X0268403Y008349*
X0268444Y0083585*
X0268477Y0083682*
X0268504Y0083782*
X0268523Y0083883*
X0268536Y0083985*
X0268541Y0084088*
X0268542Y0084114*
X0262205Y0097638D02*
D01*
X0262235Y0097639*
X0262265Y0097642*
X0262295Y0097647*
X0262324Y0097654*
X0262353Y0097664*
X0262381Y0097675*
X0262408Y0097688*
X0262434Y0097703*
X0262459Y009772*
X0262483Y0097739*
X0262505Y0097759*
X0262526Y0097781*
X0262546Y0097804*
X0262563Y0097828*
X0262579Y0097854*
X0262594Y0097881*
X0262606Y0097908*
X0262616Y0097937*
X0262625Y0097966*
X0262631Y0097995*
X0262635Y0098025*
X0262637Y0098055*
X0262637Y009807*
X0274028Y0081902D02*
D01*
X0274096Y0081975*
X0274159Y0082053*
X0274216Y0082135*
X0274268Y0082221*
X0274313Y008231*
X0274353Y0082402*
X0274385Y0082497*
X0274411Y0082594*
X027443Y0082692*
X0274442Y0082791*
X0274448Y0082891*
X0274448Y0082917*
X0278184Y0011213D02*
D01*
X0278184Y0011202*
X0278185Y0011192*
X0278187Y0011181*
X0278189Y0011171*
X0278193Y0011161*
X0278196Y0011151*
X0278201Y0011142*
X0278206Y0011133*
X0278212Y0011124*
X0278219Y0011116*
X0278226Y0011108*
X0278228Y0011106*
X0277284Y0013385D02*
D01*
X0277291Y001316*
X0277315Y0012936*
X0277354Y0012714*
X0277408Y0012496*
X0277478Y0012282*
X0277562Y0012074*
X0277661Y0011871*
X0277773Y0011677*
X0277899Y001149*
X0278038Y0011313*
X0278188Y0011146*
X0278228Y0011106*
X0261284Y0013994D02*
D01*
X0261293Y0013709*
X0261323Y0013425*
X0261373Y0013145*
X0261442Y0012868*
X026153Y0012597*
X0261636Y0012333*
X0261761Y0012077*
X0261904Y001183*
X0262063Y0011594*
X0262239Y0011369*
X0262429Y0011157*
X026248Y0011106*
X0257584Y0013421D02*
D01*
X0257591Y0013192*
X0257615Y0012965*
X0257655Y001274*
X025771Y0012518*
X0257781Y0012301*
X0257867Y0012089*
X0257967Y0011883*
X0258081Y0011686*
X0258209Y0011496*
X0258349Y0011316*
X0258502Y0011146*
X0258543Y0011106*
X0241884Y0013306D02*
D01*
X0241891Y0013089*
X0241914Y0012873*
X0241951Y0012659*
X0242004Y0012448*
X0242071Y0012242*
X0242152Y0012041*
X0242248Y0011845*
X0242356Y0011657*
X0242477Y0011477*
X0242611Y0011306*
X0242756Y0011145*
X0242795Y0011106*
X0264605Y0097993D02*
Y0103831D01*
X0238779Y001378D02*
Y0021775D01*
X0262637Y009807D02*
Y0103831D01*
X0242717Y001378D02*
Y0023676D01*
X0270511Y0084115D02*
Y0087887D01*
X0269291Y0079528D02*
Y008117D01*
X0258465Y001378D02*
Y0026527D01*
X0268542Y0084114D02*
Y0087887D01*
X0267927Y0082888D02*
X026811Y0083071D01*
X0267927Y0082887D02*
Y0082888D01*
X0261024Y0025917D02*
Y0027953D01*
X0262402Y001378D02*
Y002259D01*
X0282322Y0080384D02*
Y0087887D01*
X0274871Y0028214D02*
X0274881Y002823D01*
X027477Y0027968D02*
X0274836Y0028141D01*
X0274686Y0027825D02*
X0274688Y0027827D01*
X0274213Y001378D02*
Y0026527D01*
X0280353Y0080571D02*
Y0087887D01*
X027815Y001378D02*
Y0027478D01*
X0290549Y0027951D02*
X0290551Y0027953D01*
X0289961Y001378D02*
Y0026527D01*
X0276416Y0097993D02*
Y0103831D01*
X0293898Y001378D02*
Y0027478D01*
X0274448Y009807D02*
Y0103831D01*
X0262637Y0084672D02*
Y0087887D01*
X0260678Y0081544D02*
X0261811Y0082677D01*
X0264605Y0085784D02*
Y0087887D01*
X0262598Y0079528D02*
Y0080939D01*
X0270511Y0097993D02*
Y0103831D01*
X0268542Y009807D02*
Y0103831D01*
X0276416Y0080571D02*
Y0087887D01*
X0274448Y0082917D02*
Y0087887D01*
X0273228Y0079972D02*
Y0079969D01*
X0288227Y0082287D02*
Y0087887D01*
X0286259Y0079621D02*
Y0087887D01*
X0282322Y0097993D02*
Y0103831D01*
X0280353D02*
X0280384Y01038D01*
X0280353Y009807D02*
Y0103831D01*
X0273228Y0079528D02*
Y0079969D01*
X0274881Y002823D02*
X0274882Y0028231D01*
X0289961Y001378D02*
D01*
X0274291Y0011106D02*
X0274584Y0011399D01*
X0274084Y0011313D02*
X0274291Y0011106D01*
X0293184Y0011898D02*
X0293976Y0011106D01*
X0290039D02*
X0290784Y0011851D01*
G54D22*
X0106693Y0161417D03*
X0112205D03*
X0631496Y0274016D03*
X0637008D03*
X0631496Y0253543D03*
X0637008D03*
X0631496Y026063D03*
X0637008D03*
X0631496Y0267323D03*
X0637008D03*
X066874Y0161106D03*
X0663228D03*
X066874Y0167106D03*
X0663228D03*
X066874Y0172106D03*
X0663228D03*
X066874Y0177606D03*
X0663228D03*
X0684728Y0209606D03*
X069024D03*
X061524Y0217106D03*
X0609728D03*
X0361516Y0064567D03*
X0356004D03*
X0519882Y0292323D03*
X0525394D03*
X010748Y0237205D03*
X0112992D03*
X010748Y0184055D03*
X0112992D03*
X0111811Y0110433D03*
X0106299D03*
X0356299Y0295276D03*
X0350787D03*
X0324803Y0269685D03*
X0319291D03*
G54D23*
X0113976Y0152362D03*
Y0144882D03*
X0104528D03*
Y0148622D03*
Y0152362D03*
X0104331Y0100394D03*
Y0096653D03*
Y0092913D03*
X0113779D03*
Y0100394D03*
X0114961Y024626D03*
Y025D03*
Y025374D03*
X0105512D03*
Y024626D03*
X0114961Y019311D03*
Y019685D03*
Y0200591D03*
X0105512D03*
Y019311D03*
G54D24*
X0052165Y0112795D03*
X0052362Y0218701D03*
G54D25*
X0058858Y0112795D03*
Y0121457D03*
X0051378D03*
X0059055Y0218701D03*
Y0227362D03*
X0051575D03*
G54D26*
X0052559Y0084744D03*
Y0096358D03*
Y0189469D03*
Y0201083D03*
Y0242224D03*
Y0253839D03*
Y01375D03*
Y0149114D03*
G54D27*
X0058563Y0090551D03*
Y0195276D03*
Y0248031D03*
Y0143307D03*
G54D28*
X0213583Y0357677D03*
Y0362795D03*
X0204724Y0360236D03*
X0159941Y0357677D03*
Y0362795D03*
X0151083Y0360236D03*
X0177657Y0357677D03*
Y0362795D03*
X0168799Y0360236D03*
X0195866Y0357677D03*
Y0362795D03*
X0187008Y0360236D03*
G54D29*
X061574Y0224106D03*
Y0229106D03*
Y0234106D03*
Y0239106D03*
X0635228D03*
Y0234106D03*
Y0229106D03*
Y0224106D03*
X0683228Y0203106D03*
Y0198106D03*
Y0193106D03*
Y0188106D03*
X066374D03*
Y0193106D03*
Y0198106D03*
Y0203106D03*
G54D30*
X0185827Y0067421D03*
Y0053051D03*
G54D31*
X020161Y0422114D03*
Y0395106D03*
X019161Y0422114D03*
Y0395106D03*
X018161Y0422114D03*
Y0395106D03*
X017161Y0422114D03*
Y0395106D03*
X016161Y0422114D03*
Y0395106D03*
G54D32*
X0407805Y0176893D03*
X0392057D03*
X0407805Y0174893D03*
X0392057D03*
X0407805Y0172893D03*
X0392057D03*
X0407805Y0170893D03*
X0392057D03*
X0407805Y0168893D03*
X0392057D03*
X0407805Y0166893D03*
X0392057D03*
X0407805Y0164893D03*
X0392057D03*
X0407805Y0162893D03*
X0392057D03*
X0407805Y0160893D03*
X0392057D03*
Y0158893D03*
X0407805D03*
G54D33*
X0201772Y0378937D03*
Y0371063D03*
X0161417Y0378937D03*
Y0371063D03*
X017126Y0378937D03*
Y0371063D03*
X0181102Y0378937D03*
Y0371063D03*
G54D34*
X0455709Y0284941D03*
Y0289862D03*
X0064173Y0405217D03*
Y0410532D03*
X0084646Y0405217D03*
Y0410532D03*
X0104724Y0405217D03*
Y0410532D03*
X0124803Y0405217D03*
Y0410532D03*
G54D35*
X0237205Y0272638D03*
Y0278543D03*
X024311Y0272638D03*
Y0278543D03*
G54D36*
X0298524Y0269685D03*
X0293996D03*
G54D37*
X0097441Y025374D03*
Y0248228D03*
Y0142913D03*
Y0148425D03*
X049311Y027874D03*
Y0284252D03*
X0097441Y0196063D03*
Y0201575D03*
Y0090748D03*
Y009626D03*
G54D38*
X0523228Y0277559D03*
X051811D03*
X0523228Y0285433D03*
X051811D03*
G54D39*
X0612284Y024339D03*
Y0248823D03*
X0194488Y0067244D03*
Y0061811D03*
X0612992Y0280748D03*
Y0286181D03*
X0674984Y020889D03*
Y0214323D03*
X0623484Y021289D03*
Y0218323D03*
X07Y0187835D03*
Y0193268D03*
X0600394Y0233504D03*
Y0238937D03*
G54D40*
X0305512Y0057382D03*
Y0060728D03*
X0250394Y0057382D03*
Y0060728D03*
G54D41*
X0309646Y001378D03*
X0187599D03*
X0183661D03*
X0179725D03*
X0207283D03*
X025059D03*
X0293898D03*
X0289961D03*
X027815D03*
X0274213D03*
X0262402D03*
X0258465D03*
X0242717D03*
X0238779D03*
X0215158D03*
X0211221D03*
X0230906D03*
X0301771D03*
X0195473D03*
X0199409D03*
X0219094D03*
X0297834D03*
X0286023D03*
X0270275D03*
X0266338D03*
X0203346D03*
X0191535D03*
X0282086D03*
X0234842D03*
X0246654D03*
X0254527D03*
G54D42*
X0305709Y001573D03*
G54D43*
X0535433Y0290433D03*
Y0285433D03*
Y0280433D03*
Y0275433D03*
X0554331Y0290433D03*
Y0285433D03*
Y0280433D03*
Y0275433D03*
G54D44*
X0465158Y028998D03*
Y028498D03*
Y027998D03*
Y027498D03*
X0483661Y028998D03*
Y028498D03*
Y027998D03*
Y027498D03*
G54D45*
X0667984Y0242012D03*
Y0280201D03*
X0631984Y0146012D03*
Y0184201D03*
G54D46*
X0263779Y0362205D03*
Y0354331D03*
Y0346457D03*
Y0338583D03*
X024628Y0362205D03*
Y0346457D03*
Y0354331D03*
Y0338583D03*
G54D47*
X0221259Y0103817D03*
X029803Y0235868D03*
X0258661Y0251812D03*
X0248817D03*
X0238976D03*
X0229133D03*
X0288188Y0235868D03*
X0278345D03*
X0268502D03*
X0258661D03*
X0248817D03*
X0238976D03*
X0229133D03*
X0294093D03*
X0296061D03*
X0290157D03*
X0292125D03*
X028425D03*
X028622D03*
X0280313D03*
X0282282D03*
X0274409D03*
X0276377D03*
X0254724D03*
X0256692D03*
X0250786D03*
X0235038D03*
X0237006D03*
X0221258Y0251812D03*
X0223228D03*
Y0235868D03*
X0221258D03*
X0225196Y0251812D03*
X0227165D03*
X0240944D03*
X0242913D03*
X0235038D03*
X0237006D03*
X0250786D03*
X0252754D03*
X0244881D03*
X0246849D03*
X0260629D03*
X0254724D03*
X0262597D03*
X0256692D03*
X0225196Y0235868D03*
X0231101D03*
X0233069D03*
X0227165D03*
X0231101Y0251812D03*
X0233069D03*
X0280314Y0103817D03*
X0282283D03*
X0286221Y0087874D03*
X0288189D03*
X027441D03*
X0276378D03*
X0268503Y0103817D03*
X0270473D03*
X0258662Y0087874D03*
Y0103817D03*
X0264566Y0087874D03*
X0262598D03*
X027441Y0103817D03*
X0276378D03*
X0280314Y0087874D03*
X0282283D03*
X0268503D03*
X0270473D03*
X0262598Y0103817D03*
X0264566D03*
X0223229Y0087874D03*
X0242914D03*
X0237007D03*
X0235039D03*
X023307D03*
X0229134D03*
X0238977D03*
X0248818D03*
X0252755D03*
X0254725D03*
X0256693D03*
X0244882D03*
X024685D03*
X0225197D03*
X0227166D03*
X0256693Y0103817D03*
X0237007D03*
X0238977D03*
X0242914D03*
X024685D03*
X0248818D03*
X0244882D03*
X0229134D03*
X0227166D03*
X0225197D03*
X0223229D03*
X0235039D03*
X023307D03*
X0254725D03*
X0252755D03*
X0286221D03*
X0288189D03*
X0292126Y0087874D03*
Y0103817D03*
X0294094Y0087874D03*
Y0103817D03*
X0298031Y0087874D03*
Y0103817D03*
X0296062D03*
Y0087874D03*
X0290158Y0103817D03*
X0284251D03*
X0278346D03*
X0272441D03*
X0266535D03*
X026063D03*
X0250787D03*
X0240945D03*
X0231102D03*
X0290158Y0087874D03*
X0284251D03*
X0278346D03*
X0272441D03*
X0266535D03*
X026063D03*
X0250787D03*
X0240945D03*
X0231102D03*
X0221259D03*
X0264565Y0251812D03*
X0266534D03*
X0268502D03*
X0270472D03*
X027244D03*
X0274409D03*
X0276377D03*
X0278345D03*
X0280313D03*
X0282282D03*
X028425D03*
X028622D03*
X0288188D03*
X0290157D03*
X0292125D03*
X0294093D03*
X0296061D03*
X029803D03*
X0262597Y0235868D03*
X0266534D03*
X027244D03*
X0246849D03*
X0244881D03*
X0242913D03*
X0240944D03*
X0252754D03*
X0270472D03*
X0264565D03*
X0260629D03*
G54D48*
X0169689Y0126339D03*
X0357091D03*
X0169689Y0214331D03*
X0357091D03*
G54D49*
X0215654Y0243858D03*
Y0095827D03*
X0303646D03*
Y0243858D03*
G54D50*
X0349164Y0139823D03*
Y0137856D03*
Y0145729D03*
Y0147697D03*
Y0177225D03*
Y0149667D03*
Y0179193D03*
Y0189037D03*
Y0185099D03*
Y0187067D03*
Y0183131D03*
X0365107Y0187067D03*
Y0189037D03*
Y0192973D03*
X0349164Y0133918D03*
Y0135887D03*
X0365107Y0179193D03*
Y0177225D03*
Y0185099D03*
Y0183131D03*
Y0194941D03*
Y0198879D03*
Y0196911D03*
X0349164Y0198879D03*
Y0196911D03*
X0365107Y0169351D03*
X0349164Y0163445D03*
Y0167383D03*
Y0165415D03*
Y0169351D03*
X0365107Y0173289D03*
Y0175257D03*
Y0165415D03*
Y0157541D03*
Y0155571D03*
Y0167383D03*
Y0163445D03*
X0349164Y0192973D03*
Y0155571D03*
Y0200848D03*
Y0191005D03*
Y0181163D03*
Y0171319D03*
Y0161477D03*
Y0151635D03*
Y0141793D03*
X0365107Y0200848D03*
Y0191005D03*
Y0181163D03*
Y0171319D03*
Y0161477D03*
Y0151635D03*
Y0141793D03*
X0349164Y0194941D03*
X0365107Y0159509D03*
X0349164Y0153603D03*
X0365107Y0149667D03*
Y0147697D03*
Y0145729D03*
Y0143761D03*
Y0139823D03*
Y0137856D03*
Y0135887D03*
Y0133918D03*
X0349164Y0131949D03*
X0365107D03*
X0349164Y0173289D03*
Y0175257D03*
X0365107Y0153603D03*
X0349164Y0157541D03*
Y0159509D03*
Y0143761D03*
Y0208721D03*
Y0206752D03*
Y0204784D03*
Y0202816D03*
X0365107Y0208721D03*
Y0206752D03*
Y0204784D03*
Y0202816D03*
X0177617Y016345D03*
Y0161481D03*
Y0187072D03*
Y0202819D03*
Y0191008D03*
Y0183134D03*
Y0194946D03*
Y0173293D03*
Y0177229D03*
X0161672Y0192977D03*
Y0185103D03*
Y0191008D03*
Y0202819D03*
X0177617Y0200851D03*
Y0196915D03*
Y0145733D03*
Y0167386D03*
X0161672Y0187072D03*
Y0196915D03*
X0177617Y0192977D03*
Y0185103D03*
Y0181167D03*
Y0165419D03*
X0161672Y0200851D03*
X0177617Y017526D03*
Y0171324D03*
X0161672Y0194946D03*
X0177617Y0155576D03*
Y0157545D03*
X0161672Y0151638D03*
Y0145733D03*
Y0181167D03*
Y0183134D03*
X0177617Y0143764D03*
X0161672Y013589D03*
X0177617Y0133923D03*
X0161672Y0157545D03*
Y0143764D03*
Y0153607D03*
Y0155576D03*
Y0161481D03*
Y0173293D03*
Y0167386D03*
Y0137859D03*
Y0147702D03*
Y0141797D03*
Y017526D03*
X0177617Y013589D03*
X0161672Y0133923D03*
Y016345D03*
Y0177229D03*
X0177617Y0137859D03*
Y0131954D03*
Y0141797D03*
X0161672Y0131954D03*
X0177617Y0147702D03*
X0161672Y0171324D03*
Y0165419D03*
X0177617Y0151638D03*
X0161672Y0204788D03*
X0177617D03*
Y0139828D03*
Y0149671D03*
Y0159512D03*
Y0169355D03*
Y0179198D03*
Y0189041D03*
Y0198882D03*
X0161672Y0139828D03*
Y0149671D03*
Y0159512D03*
Y0169355D03*
Y0179198D03*
Y0189041D03*
Y0198882D03*
Y0208726D03*
X0177617D03*
Y0206756D03*
Y0153607D03*
X0161672Y0206756D03*
G54D51*
X0318848Y0285433D03*
Y0283465D03*
Y0281496D03*
Y0279528D03*
X0328789D03*
Y0281496D03*
Y0283465D03*
Y0285433D03*
G54D52*
X032185Y0278494D03*
X0323819D03*
X0325787D03*
Y0286467D03*
X0323819D03*
X032185D03*
G54D53*
X0357382Y0281201D03*
Y0278642D03*
X0349311D03*
Y0281201D03*
Y028376D03*
Y0286319D03*
X0357382D03*
Y028376D03*
G54D54*
X0301969Y0277298D03*
X0294488D03*
Y0285694D03*
X0298228D03*
G54D55*
X0301969Y0285694D03*
G54D56*
X0124984Y0419752D03*
Y0425461D03*
X0619291Y0282185D03*
Y0287894D03*
X0064484Y0425461D03*
Y0419752D03*
X0084651Y0425461D03*
Y0419752D03*
X0104818D03*
Y0425461D03*
G54D57*
X0355409Y0072606D03*
X0362496D03*
X0670028Y0142106D03*
X0662941D03*
X0670028Y0153106D03*
X0662941D03*
G54D58*
X0606484Y0238764D03*
Y0233449D03*
X0693984Y0187949D03*
Y0193264D03*
G54D59*
X0337598Y0269685D03*
Y0275197D03*
X021063Y0062992D03*
Y0068504D03*
X0286417Y0338386D03*
Y0332874D03*
X0270669Y0319685D03*
Y0314173D03*
X0285433Y027874D03*
Y0284252D03*
X05Y0289173D03*
Y0283661D03*
X0366142Y0295276D03*
Y0289764D03*
G54D60*
X0651984Y0201756D03*
Y0195457D03*
X0646984Y0230256D03*
Y0223957D03*
G54D61*
X0201969Y0062992D03*
Y0070079D03*
X0633484Y021815D03*
Y0211063D03*
X0665984Y0209563D03*
Y021665D03*
X0627559Y0282283D03*
Y028937D03*
X0636221Y0282283D03*
Y028937D03*
X0295276Y0332677D03*
Y0339764D03*
X0261811Y0321457D03*
Y031437D03*
G54D62*
X0684268Y0181606D03*
X0689701D03*
X0673661Y018189D03*
X0679095D03*
X0631142Y0246063D03*
X0636575D03*
X0139252Y0151575D03*
X0144685D03*
G54D108*
X0009984Y0258106D03*
Y0238106D03*
X0029984D03*
Y0258106D03*
X0009984Y0100606D03*
Y0080606D03*
X0029984D03*
Y0100606D03*
X0009984Y0153106D03*
Y0133106D03*
X0029984D03*
Y0153106D03*
X0009984Y0205606D03*
Y0185606D03*
X0029984D03*
Y0205606D03*
G54D112*
X0240847Y0231588D02*
D01*
X024085Y0231643*
X0240851Y0231669*
X0455804Y028498D02*
D01*
X0455794Y0284979*
X0455785Y0284978*
X0455776Y0284977*
X0455767Y0284974*
X0455758Y0284971*
X0455749Y0284968*
X0455741Y0284964*
X0455732Y0284959*
X0455725Y0284954*
X0455717Y0284948*
X045571Y0284942*
X0455709Y0284941*
Y0289863D02*
D01*
X0455708Y0289862*
X0455708Y0289862*
X0455708Y0289862*
X0455708Y0289862*
X0455709Y0289862*
X0455994Y028998D02*
D01*
X0455965Y0289979*
X0455937Y0289976*
X045591Y0289971*
X0455882Y0289964*
X0455856Y0289955*
X045583Y0289945*
X0455804Y0289932*
X045578Y0289918*
X0455757Y0289903*
X0455734Y0289885*
X0455714Y0289866*
X0455709Y0289863*
X0292898Y0016194D02*
D01*
X0292906Y0015955*
X0292931Y0015718*
X0292972Y0015484*
X029303Y0015252*
X0293103Y0015026*
X0293193Y0014805*
X0293297Y0014591*
X0293416Y0014384*
X029355Y0014187*
X0293696Y0013999*
X0293856Y0013822*
X0293898Y001378*
X0045276Y0112205D02*
X0051575D01*
X0052165Y0112795*
X0045276Y0121063D02*
X0050984D01*
X0051378Y0121457*
X004626Y0227362D02*
X0051575D01*
X0052165Y0218504D02*
X0052362Y0218701D01*
X004626Y0218504D02*
X0052165D01*
X005876Y0195472D02*
X0059055Y0195768D01*
X0058563Y0195276D02*
X005876Y0195472D01*
X0059055Y0195768D02*
Y0218701D01*
X0058563Y0248031D02*
X0059055Y0247539D01*
X0058488Y0248106D02*
X0058563Y0248031D01*
X0059055Y0227362D02*
Y0247539D01*
X0058508Y0090606D02*
X0058858Y0090957D01*
X0058563Y0090551D02*
X0059153Y0091142D01*
X0058858Y0090957D02*
Y0112795D01*
X0058563Y0121752D02*
Y0143307D01*
Y0121752D02*
X0058858Y0121457D01*
X0107283Y0169291D02*
X0112205Y016437D01*
Y0157874D02*
Y016437D01*
Y0110827D02*
Y0117126D01*
X0111811Y0110433D02*
X0112205Y0110827D01*
X0350394Y0303118D02*
Y030315D01*
Y0295669D02*
Y0303118D01*
X032874Y0292421D02*
X0329918D01*
X0108268Y0092913D02*
X0109055Y0093701D01*
X0104331Y0092913D02*
X0108268D01*
X0109055Y0093701D02*
Y0099606D01*
X0097441Y009626D02*
X0097835Y0096653D01*
X0104331*
X011437Y0093504D02*
X011752D01*
X0113779Y0092913D02*
X011437Y0093504D01*
X011752D02*
X0119587Y0091437D01*
X0059153Y0091142D02*
X0097047D01*
X0097441Y0090748*
X0058563Y0248031D02*
X0097244D01*
X0097441Y0248228*
X0105315Y0200787D02*
X0105512Y0200591D01*
X0098228Y0200787D02*
X0105315D01*
X0097441Y0201575D02*
X0098228Y0200787D01*
X009685Y0195472D02*
X0097441Y0196063D01*
X005876Y0195472D02*
X009685D01*
X0097638Y0148622D02*
X0104528D01*
X0097441Y0148425D02*
X0097638Y0148622D01*
X0113976Y0144882D02*
X0114173Y0144685D01*
X0117992D02*
X0119173Y0143504D01*
X011939*
X0114173Y0144685D02*
X0117992D01*
X0101378Y0161417D02*
X0106693D01*
X0104528Y0155709D02*
X0106299Y015748D01*
X0104528Y0152362D02*
X0104724Y0152559D01*
X0104528Y0152362D02*
Y0155709D01*
X0104331Y0144685D02*
X0104528Y0144882D01*
X0106299Y0161024D02*
X0106693Y0161417D01*
X0113976Y0152362D02*
Y0156102D01*
X0112205Y0157874D02*
X0113976Y0156102D01*
X0109252Y0145669D02*
Y0150591D01*
X0108465Y0144882D02*
X0109252Y0145669D01*
X0107283Y0152559D02*
X0109252Y0150591D01*
X0104528Y0144882D02*
X0108465D01*
X0106299Y015748D02*
Y0161024D01*
X0104724Y0152559D02*
X0107283D01*
X0097441Y0147441D02*
Y0147447D01*
X0058563Y0143307D02*
X0097047D01*
X0097441Y0142913*
X0270669Y0309087D02*
Y0314173D01*
X0261811Y0309055D02*
Y031437D01*
X0249938Y0283527D02*
D01*
X0254724Y027874*
X0356299Y0291339D02*
Y0303118D01*
X0366142Y0295276D02*
Y0303118D01*
X024311Y0267748D02*
Y0272638D01*
X0244881Y0251812D02*
Y0260235D01*
X0244882Y0260236*
X0252847Y022924D02*
X0252953Y0229134D01*
X0252847Y022924D02*
Y0235775D01*
X0246849Y0230608D02*
X0248107Y022935D01*
X0246849Y0230608D02*
Y0235868D01*
X0248107Y0229134D02*
Y022935D01*
X0237205Y0267717D02*
Y0272638D01*
X0258661Y024168D02*
X025889Y024191D01*
Y0242126*
X0258661Y0235868D02*
Y024168D01*
X0525591Y0271654D02*
X052937Y0275433D01*
X0525591Y0271654D02*
D01*
X052937Y0275433D02*
X0535433D01*
X0514764Y0277559D02*
X051811D01*
X0512795Y0279528D02*
X0514764Y0277559D01*
X0512795Y028248D02*
X0515748Y0285433D01*
X051811*
X0519685Y029252D02*
X0519882Y0292323D01*
X0519685Y029252D02*
Y0298228D01*
X0490158Y0270638D02*
Y0273622D01*
X0488799Y027498D02*
X0490158Y0273622D01*
X0483661Y027498D02*
X0488799D01*
X0500197Y0283465D02*
X0505905D01*
X05Y0283661D02*
X0500197Y0283465D01*
X0279528Y0284449D02*
X0285236D01*
X0286221Y0283465*
X028937*
X0323727Y0278586D02*
X0323819Y0278494D01*
X0323727Y0278586D02*
Y0280136D01*
X0322366Y0281496D02*
X0323727Y0280136D01*
X0318848Y0281496D02*
X0322366D01*
X0324803Y0269685D02*
X0325787Y0270669D01*
Y0278494*
X0161122Y021939D02*
X0187008Y0245276D01*
X0161122Y0208858D02*
Y021939D01*
X0111024Y024626D02*
X0114961D01*
X0110236Y0247047D02*
X0111024Y024626D01*
X0110236Y0247047D02*
Y0251969D01*
X0112008Y025374*
X0114961*
X0110236Y0193898D02*
X0111024Y019311D01*
X0114961*
X0110236Y0193898D02*
Y0199803D01*
X0111024Y0200591D02*
X0114961D01*
X0110236Y0199803D02*
X0111024Y0200591D01*
X0108268Y0100394D02*
X0109055Y0099606D01*
X0104331Y0100394D02*
X0108268D01*
X0202756Y0409449D02*
Y0420968D01*
X020161Y0422114D02*
X0202756Y0420968D01*
X029685Y0332677D02*
X0302165D01*
X0296063Y0333465D02*
X029685Y0332677D01*
X0286417Y0327756D02*
Y0332874D01*
X0285433Y0274606D02*
Y027874D01*
Y0274606D02*
X0290354Y0269685D01*
X0293996*
X0294488Y0270177D02*
Y0277298D01*
X0293996Y0269685D02*
X0294488Y0270177D01*
X0288059Y0241869D02*
X0288123Y0241805D01*
Y0235932D02*
X0288188Y0235868D01*
X0288123Y0235932D02*
Y0241805D01*
X026847Y02359D02*
Y0241798D01*
X0268437Y0241831D02*
X026847Y0241798D01*
Y02359D02*
X0268502Y0235868D01*
X0238976Y0240727D02*
X0240158Y024191D01*
X0238976Y0235868D02*
Y0240727D01*
X0240158Y024191D02*
Y0242126D01*
X0160433Y0409665D02*
X016161Y0410843D01*
Y0422114*
X0160433Y0409449D02*
Y0409665D01*
X0213592Y0357686D02*
X0217479D01*
X0217488Y0357695*
X0213583Y0357677D02*
X0213592Y0357686D01*
X0201772Y0070276D02*
Y0076772D01*
Y0070276D02*
X0201969Y0070079D01*
X0211024Y0068898D02*
X0216535D01*
X021063Y0068504D02*
X0211024Y0068898D01*
X0107315Y0177134D02*
X0109283D01*
X0134843Y0151575*
X0107283Y0177165D02*
X0107315Y0177134D01*
X028937Y0283465D02*
X0291339Y0281496D01*
X0297244*
X0298228Y028248*
Y0285694*
X0311024Y0281496D02*
X0318848D01*
X0311024Y0283465D02*
X0318848D01*
X0311024Y0285433D02*
X0318848D01*
X0324803Y0269685D02*
X0331693D01*
X0337598D02*
X0343504D01*
X0349311Y0278642D02*
X0351279D01*
X0357283Y0272638*
Y0286417D02*
X0357382Y0286319D01*
X0353346Y0286417D02*
X0357283D01*
X03496Y0284049D02*
X0350978D01*
X0353346Y0286417*
X0349311Y028376D02*
X03496Y0284049D01*
X0357382Y0286319D02*
Y0290256D01*
X0356299Y0291339D02*
X0357382Y0290256D01*
X0313976Y0339567D02*
X033563D01*
X0371477Y030372*
Y0289616D02*
Y030372D01*
X0313976Y0339567D02*
X0350394Y030315D01*
X0304134Y0339567D02*
X0313976D01*
X0329918Y0292421D02*
Y0313783D01*
Y0292362D02*
Y0292421D01*
X0304134Y0339567D02*
X0329918Y0313783D01*
X0312894Y0273721D02*
X0312992Y0273622D01*
Y0272638D02*
Y0273622D01*
X0315945Y0269685D02*
X0319291D01*
X0312992Y0272638D02*
X0315945Y0269685D01*
X0337598Y0275197D02*
X0337992Y027559D01*
X0343504*
X0332677Y0277067D02*
X0334547Y0275197D01*
X0337598*
X0366142Y0289764D02*
X0366289Y0289616D01*
X0371477*
X0366043Y0289665D02*
X0366142Y0289764D01*
X0366043Y0284941D02*
Y0289665D01*
X0364862Y028376D02*
X0366043Y0284941D01*
X0350394Y0295669D02*
X0350787Y0295276D01*
Y0289665D02*
Y0295276D01*
X0254724Y027874D02*
X0285433D01*
X0290158Y0103739D02*
Y011063D01*
X0284251Y0103739D02*
Y0109626D01*
X0285039Y0110413*
Y011063*
X027874Y0110413D02*
Y011063D01*
X0278346Y011002D02*
X027874Y0110413D01*
X0278346Y0103739D02*
Y011002D01*
X0272835Y0110413D02*
Y011063D01*
X0272441Y0110019D02*
X0272835Y0110413D01*
X0272441Y0103739D02*
Y0110019D01*
X023002Y0060728D02*
X0305512D01*
X0207087Y0037795D02*
X023002Y0060728D01*
X0612992Y0276772D02*
Y0280748D01*
X027244Y0229746D02*
Y0235868D01*
X0272638Y0229331D02*
Y0229547D01*
X027244Y0229746D02*
X0272638Y0229547D01*
X0263779Y0354331D02*
X0271654D01*
X0263779Y0346457D02*
X0271654D01*
X0263779Y0362205D02*
X0271654D01*
X0238189D02*
X024628D01*
X0238189Y0346457D02*
X024628D01*
X0238189Y0354331D02*
X024628D01*
X0631642Y0145669D02*
X0631984Y0146012D01*
X0134843Y0151575D02*
X0139252D01*
X0107283Y0177165D02*
Y0183858D01*
X010748Y0184055*
Y0187303*
X0105413Y018937D02*
X010748Y0187303D01*
X0107283Y0231299D02*
Y0237008D01*
X010748Y0237205*
Y0241142*
X0112992Y0237205D02*
X0113189Y0237402D01*
Y0241142*
X0114961Y0242913D02*
Y024626D01*
X0113189Y0241142D02*
X0114961Y0242913D01*
X0113189Y0184252D02*
Y0187992D01*
X0112992Y0184055D02*
X0113189Y0184252D01*
X0114961Y0189764D02*
Y019311D01*
X0113189Y0187992D02*
X0114961Y0189764D01*
X0106102Y0110236D02*
X0106299Y0110433D01*
X0106102Y0106496D02*
Y0110236D01*
X0104331Y0100394D02*
Y0104724D01*
X0106102Y0106496*
X0101181Y0110433D02*
X0106299D01*
X0112992Y0184055D02*
X011811D01*
X0112992Y0237205D02*
X011811D01*
X0115157Y0200787D02*
X0120079D01*
X0114961Y0200591D02*
X0115157Y0200787D01*
X0114961Y025374D02*
X0115157Y0253937D01*
X0120079*
X0160039Y0357579D02*
X0163858D01*
X0163957Y035748*
X0159941Y0357677D02*
X0160039Y0357579D01*
X0199587Y0357283D02*
X0199803D01*
X0195866Y0357677D02*
X0199193D01*
X0199587Y0357283*
X0213583Y0362795D02*
X0213823Y0363036D01*
X0217367*
X021752Y0363189*
X0195866Y0362795D02*
X0196107Y0363036D01*
X019965*
X0199803Y0363189*
X0177708Y0362846D02*
X0181744D01*
X0177657Y0362795D02*
X0177708Y0362846D01*
X0181744D02*
X0181794Y0362897D01*
X0159957Y0362811D02*
X0163992D01*
X018161Y0410173D02*
Y0414614D01*
X0181102Y0409665D02*
X018161Y0410173D01*
X0181102Y0409449D02*
Y0409665D01*
X0173228Y0409449D02*
Y0420496D01*
X017161Y0422114D02*
X0173228Y0420496D01*
X0064484Y0425461D02*
Y0429425D01*
X0064961Y0429902D02*
Y0430118D01*
X0064484Y0429425D02*
X0064961Y0429902D01*
X0084646Y0425466D02*
Y0430118D01*
X0104331Y0425948D02*
Y0430118D01*
X0124984Y0425461D02*
X0125Y0425476D01*
Y0430118*
X0104331Y0425948D02*
X0104818Y0425461D01*
X0084646Y0425466D02*
X0084651Y0425461D01*
X0288123Y0246522D02*
Y0251747D01*
X0288059Y0246457D02*
X0288123Y0246522D01*
X032185Y0286467D02*
Y0292323D01*
X0320866Y0293307D02*
X032185Y0292323D01*
X030115Y0291122D02*
Y0291307D01*
Y0291122D02*
X0301969Y0290303D01*
Y0285694D02*
Y0290303D01*
X0325787Y0289469D02*
X032874Y0292421D01*
X0324803Y0293091D02*
Y0293276D01*
X0323819Y0292106D02*
X0324803Y0293091D01*
X0357529Y0281348D02*
X0362057D01*
X0357382Y0281201D02*
X0357529Y0281348D01*
X0362057D02*
X0362205Y0281496D01*
X0357406Y0278617D02*
X0362131D01*
X0357382Y0278642D02*
X0357406Y0278617D01*
X0362131D02*
X0362156Y0278592D01*
X0294341Y0291289D02*
X0294414Y0291215D01*
Y0285768D02*
X0294488Y0285694D01*
X0294414Y0285768D02*
Y0291215D01*
X0323819Y0286467D02*
Y0292106D01*
X0325787Y0286467D02*
Y0289469D01*
X032185Y0286467D02*
D01*
X0280313Y0235868D02*
X0280405Y0235775D01*
Y0229437D02*
Y0235775D01*
Y0229437D02*
X0280512Y0229331D01*
X0258752Y0246594D02*
Y0251719D01*
Y0246594D02*
X025889Y0246457D01*
X0293069Y0257766D02*
Y0257983D01*
X0292125Y0256822D02*
X0293069Y0257766D01*
X0292125Y0251812D02*
Y0256822D01*
X0298031Y0260531D02*
D01*
X0247638Y026002D02*
Y0260236D01*
X0290108Y025186D02*
Y0260581D01*
X0298031Y0251812D02*
Y0260531D01*
X0246849Y0251812D02*
Y0259231D01*
X0247638Y026002*
X0290059Y026063D02*
X0290108Y0260581D01*
X0229133Y0246652D02*
Y0251812D01*
X0229035Y0246555D02*
X0229133Y0246652D01*
X0288123Y0251747D02*
X0288188Y0251812D01*
X0298524Y0269685D02*
X0298622Y0269587D01*
X0317913Y0181102D02*
X0331693Y0167323D01*
X0386372Y0163466D02*
X0386504D01*
X0387078Y0162893*
X0392057*
X0349178Y0171305D02*
X0354317D01*
X0365093D02*
X0365107Y0171319D01*
X036025Y0171305D02*
X0365093D01*
X037297Y0167353D02*
X0373031Y0167291D01*
X0360236Y0171291D02*
X036025Y0171305D01*
X0365137Y0167353D02*
X037297D01*
X0349164Y0171319D02*
X0349178Y0171305D01*
X0354317D02*
X0354331Y0171291D01*
X0300787Y0269685D02*
X0305118D01*
X0298524D02*
X0300787D01*
X0317913Y0181102D02*
Y025689D01*
X0305118Y0269685D02*
X0317913Y025689D01*
X0523228Y0281496D02*
Y0285433D01*
X0535433*
X0523228Y0281496D02*
D01*
Y0273622D02*
D01*
Y0277559D01*
X029808Y0229282D02*
X029813Y0229232D01*
X0286024D02*
X0286127Y0229336D01*
X029808Y0229282D02*
Y0235818D01*
X0286127Y0229336D02*
Y0235775D01*
X029803Y0235868D02*
X029808Y0235818D01*
X0268595Y0246563D02*
Y0251719D01*
Y0246563D02*
X0268701Y0246457D01*
X0254724Y0230532D02*
Y0235868D01*
Y0230532D02*
X0255906Y022935D01*
Y0229134D02*
Y022935D01*
X0244882Y0231298D02*
X0245521Y0230659D01*
Y0228891D02*
Y0230659D01*
Y0228891D02*
X0245674Y0228738D01*
X0242913Y0229745D02*
Y0235868D01*
Y0229745D02*
X0243307Y022935D01*
Y0229134D02*
Y022935D01*
X0231053Y0229084D02*
Y0235819D01*
X0231101Y0235868*
X0231004Y0229035D02*
X0231053Y0229084D01*
X0290108Y025186D02*
X0290157Y0251812D01*
X0338613Y0202786D02*
X0349134D01*
X0338583Y0202756D02*
X0338613Y0202786D01*
X0349134D02*
X0349164Y0202816D01*
X0338583Y0204724D02*
X0338613Y0204754D01*
X0349133D02*
X0349164Y0204784D01*
X0338613Y0204754D02*
X0349133D01*
X0349134Y0206723D02*
X0349164Y0206752D01*
X0338613Y0206723D02*
X0349134D01*
X0338583Y0206693D02*
X0338613Y0206723D01*
X0338583Y0208661D02*
X0338613Y0208692D01*
X0349133D02*
X0349164Y0208721D01*
X0338613Y0208692D02*
X0349133D01*
X0365138D02*
X0373002D01*
X0365107Y0208721D02*
X0365138Y0208692D01*
X0373002D02*
X0373031Y0208661D01*
X0373002Y0206723D02*
X0373031Y0206693D01*
X0365107Y0206752D02*
X0365137Y0206723D01*
X0373002*
X0365138Y0204754D02*
X0373001D01*
X0373031Y0204724*
X0365107Y0204784D02*
X0365138Y0204754D01*
X0365137Y0202786D02*
X0373002D01*
X0365107Y0202816D02*
X0365137Y0202786D01*
X0373002D02*
X0373031Y0202756D01*
X0365138Y0189006D02*
X0373001D01*
X0373031Y0188976*
X0365107Y0189037D02*
X0365138Y0189006D01*
X037189Y0179193D02*
X0372815Y0180118D01*
X0365107Y0179193D02*
X037189D01*
X0372815Y0180118D02*
X0373031D01*
X0365138Y0177195D02*
X0373001D01*
X0373031Y0177165*
X0365107Y0177225D02*
X0365138Y0177195D01*
X0365107Y0167383D02*
X0365137Y0167353D01*
X0354301Y0141762D02*
X0354331Y0141732D01*
X0349164Y0141793D02*
X0349194Y0141762D01*
X0354301*
X0365077D02*
X0365107Y0141793D01*
X0360266Y0141762D02*
X0365077D01*
X0360236Y0141732D02*
X0360266Y0141762D01*
X0365078Y0151605D02*
X0365107Y0151635D01*
X0360266Y0151605D02*
X0365078D01*
X0360236Y0151575D02*
X0360266Y0151605D01*
X0349193D02*
X0354301D01*
X0349164Y0151635D02*
X0349193Y0151605D01*
X0354301D02*
X0354331Y0151575D01*
X0349194Y0161447D02*
X0354301D01*
X0349164Y0161477D02*
X0349194Y0161447D01*
X0354301D02*
X0354331Y0161417D01*
X0360266Y0161447D02*
X0365077D01*
X0365107Y0161477*
X0360236Y0161417D02*
X0360266Y0161447D01*
X0349164Y0181163D02*
X0349194Y0181132D01*
X0354301*
X0354331Y0181102*
X0360266Y0181132D02*
X0365077D01*
X0365107Y0181163*
X0360236Y0181102D02*
X0360266Y0181132D01*
X0349164Y0191005D02*
X0349193Y0190975D01*
X0354301*
X0354331Y0190945*
X0365078Y0190975D02*
X0365107Y0191005D01*
X0360266Y0190975D02*
X0365078D01*
X0360236Y0190945D02*
X0360266Y0190975D01*
X0365077Y0200817D02*
X0365107Y0200848D01*
X0360236Y0200787D02*
X0360266Y0200817D01*
X0365077*
X0349164Y0200848D02*
X0349194Y0200817D01*
X0354301*
X0354331Y0200787*
X0113779Y0100394D02*
Y0104626D01*
X0111811Y0106595D02*
X0113779Y0104626D01*
X0111811Y0106595D02*
Y0110433D01*
X0058508Y0090606D02*
X0058563Y0090551D01*
X0019984Y0090606D02*
X0058508D01*
X0019984Y0143106D02*
X0058362D01*
X0058563Y0143307*
X0105413Y018937D02*
Y0193012D01*
X0105512Y019311*
Y024311D02*
Y024626D01*
Y024311D02*
X010748Y0241142D01*
X0097441Y025374D02*
X0105512D01*
X0019984Y0248106D02*
X0058488D01*
X0019984Y0195606D02*
X0058232D01*
X0058563Y0195276*
X0351673Y0281201D02*
X0354232Y028376D01*
X0357382*
X0349311Y0281201D02*
X0351673D01*
X0357382Y028376D02*
X0364862D01*
X0349311Y0286319D02*
X034941Y0286417D01*
Y0288287*
X0350787Y0289665*
X0328789Y0279528D02*
X0328882Y0279435D01*
X0331194*
X0332677Y0277953*
Y0277067D02*
Y0277953D01*
X0319291Y0269685D02*
Y0273228D01*
X032185Y0275787D02*
Y0278494D01*
X0319291Y0273228D02*
X032185Y0275787D01*
X0301969Y0270866D02*
Y0277298D01*
X0300787Y0269685D02*
X0301969Y0270866D01*
X0228051Y0259823D02*
Y0260039D01*
X0227165Y0251812D02*
Y0258936D01*
X0228051Y0259823*
X0182735Y0208739D02*
X0184144Y0210148D01*
X0175244Y0208739D02*
X0182735D01*
X0170177Y0233661D02*
X0183465Y0246949D01*
X0166437Y0233661D02*
X0170177D01*
X0151083Y0353346D02*
X0183465Y0320965D01*
Y0246949D02*
Y0320965D01*
X016939Y023002D02*
X0184843Y0245472D01*
X0162992Y0212992D02*
Y0218996D01*
X0204724Y0260728D02*
Y0360236D01*
X0162992Y0218996D02*
X0204724Y0260728D01*
X0184843Y0245472D02*
Y0322539D01*
X0164961Y023002D02*
X016939D01*
X0187008Y0245276D02*
Y0360236D01*
X0162992Y0212992D02*
X016624Y0209744D01*
X0151083Y0353346D02*
Y0360236D01*
X0168799Y0338583D02*
Y0360236D01*
Y0338583D02*
X0184843Y0322539D01*
X0161686Y020677D02*
X0161765Y0206849D01*
X0161672Y0206756D02*
X0161686Y020677D01*
X016624Y0208053D02*
Y0209744D01*
X0161765Y0206849D02*
X0165035D01*
X016624Y0208053*
X0184212Y0207604D02*
X0184429D01*
X0177655Y020677D02*
X0183378D01*
X0184212Y0207604*
X0341142Y0142421D02*
X034374Y0139823D01*
X0349164*
X0342558Y0137856D02*
X0349164D01*
X0341142Y0139272D02*
X0342558Y0137856D01*
X03415Y0136314D02*
X0341928Y0135887D01*
X0341283Y0136314D02*
X03415D01*
X0341928Y0135887D02*
X0349164D01*
X0341398Y0133918D02*
X0349163D01*
X0341397Y0133917D02*
X0341398Y0133918D01*
X0349163D02*
X0349164D01*
X0177685Y0151623D02*
X0188929D01*
X0188944Y0151607*
X0240613Y0229269D02*
X0240847Y0231588D01*
X0240851Y0231669D02*
Y0235775D01*
X0114961Y025D02*
X0115157Y0250197D01*
X011998*
X0114961Y019685D02*
X0115059Y0196752D01*
X0119685*
X0286127Y0235775D02*
X028622Y0235868D01*
X0278254Y023596D02*
X0278345Y0235868D01*
X0278254Y023596D02*
Y023884D01*
X0278248Y0238845D02*
X0278254Y023884D01*
X0278248Y0238845D02*
Y0241831D01*
X0266486Y0235819D02*
X0266534Y0235868D01*
X0266486Y0229183D02*
Y0235819D01*
X0266437Y0229134D02*
X0266486Y0229183D01*
X0262598Y0229134D02*
Y0235867D01*
X0262597Y0235868D02*
X0262598Y0235867D01*
Y0229134D02*
D01*
X0256692Y0235868D02*
X0256784Y0235775D01*
Y0231799D02*
X0259547Y0229035D01*
X0256784Y0231799D02*
Y0235775D01*
X0252754Y0235868D02*
X0252847Y0235775D01*
X0248818Y0235868D02*
Y024183D01*
X0248817Y0235868D02*
X0248818D01*
Y024183D02*
X0248819Y0241831D01*
X0244882Y0231298D02*
Y0235866D01*
X0244881Y0235868D02*
X0244882Y0235866D01*
X0240851Y0235775D02*
X0240944Y0235868D01*
X0233069Y0229745D02*
Y0235868D01*
Y0229745D02*
X0233563Y0229252D01*
Y0229035D02*
Y0229252D01*
X0229133Y0240767D02*
X023002Y0241654D01*
Y024187*
X0229133Y0235868D02*
Y0240767D01*
X029803Y0251812D02*
X0298031D01*
X0278345D02*
X0278437Y0251719D01*
Y0246563D02*
Y0251719D01*
Y0246563D02*
X0278543Y0246457D01*
X0238976Y0251812D02*
X0239068Y0251719D01*
Y0246562D02*
Y0251719D01*
Y0246562D02*
X0239173Y0246457D01*
X0248817Y0247265D02*
X024941Y0246673D01*
X0248817Y0247265D02*
Y0251812D01*
X024941Y0246457D02*
Y0246673D01*
X0258661Y0251812D02*
X0258752Y0251719D01*
X0268502Y0251812D02*
X0268595Y0251719D01*
X0492913Y0278543D02*
X049311Y027874D01*
X0492913Y0274803D02*
Y0278543D01*
X0523228Y0277559D02*
X0527165D01*
X0530039Y0280433*
X0535433*
X055437Y0290394D02*
X0564921D01*
X0564961Y0290354*
X0554331Y0285433D02*
X0570866D01*
X0401728Y0157633D02*
X0402712D01*
X0401575Y015748D02*
X0401728Y0157633D01*
X0489173Y0284449D02*
X0492913D01*
X049311Y0284252*
X0488642Y028498D02*
X0489173Y0284449D01*
X0483661Y028498D02*
X0488642D01*
X0455217Y0284449D02*
X0455709Y0284941D01*
X0455804Y028498D02*
X0465158D01*
X0455217Y028937D02*
X0455709Y0289862D01*
X0455994Y028998D02*
X0465158D01*
X0449803Y028937D02*
X0455217D01*
X0449803Y0284449D02*
X0455217D01*
X0392057Y0164893D02*
X039696D01*
X0397683Y0165616D02*
X0397899D01*
X039696Y0164893D02*
X0397683Y0165616D01*
X0401575Y0168307D02*
X0402989Y0166893D01*
X0407805*
X0402321Y0172893D02*
X0407805D01*
X040175Y0172321D02*
X0402321Y0172893D01*
X0401533Y0172321D02*
X040175D01*
X0386371Y017815D02*
X0387628Y0176893D01*
X0392057*
X0386433Y0160893D02*
X0392057D01*
X0386433D02*
D01*
X0391965Y01588D02*
X0392057Y0158893D01*
X0386674Y0157787D02*
X0387688Y01588D01*
X0386458Y0157787D02*
X0386674D01*
X0387688Y01588D02*
X0391965D01*
X0402436Y0174893D02*
X0407805D01*
X0401461Y0175652D02*
X0401677D01*
X0402436Y0174893*
X0401791Y017815D02*
X0403048Y0176893D01*
X0401575Y017815D02*
X0401791D01*
X0403048Y0176893D02*
X0407805D01*
X0407713Y01588D02*
X0407805Y0158893D01*
X0403879Y01588D02*
X0407713D01*
X0402712Y0157633D02*
X0403879Y01588D01*
X0401575Y0165354D02*
X0401791D01*
X0402253Y0164893D02*
X0407805D01*
X0401791Y0165354D02*
X0402253Y0164893D01*
X0407775Y0162863D02*
X0407805Y0162893D01*
X0401575Y0162833D02*
X0401605Y0162863D01*
X0407775*
X0401575Y0160433D02*
X0401791D01*
X0402251Y0160893*
X0407805*
X0554331Y0275433D02*
X055439Y0275492D01*
X0564862*
X0564921Y0275551*
X055437Y0280472D02*
X0564921D01*
X0564961Y0280512*
X0554331Y0280433D02*
X055437Y0280472D01*
X0554331Y0290433D02*
X055437Y0290394D01*
X0177655Y0151652D02*
X0177685Y0151623D01*
X0144685Y0151575D02*
X0149606D01*
X0684335Y0203828D02*
Y0209606D01*
X0693177Y0193106D02*
X0693984Y0192299D01*
X0615634Y0217106D02*
Y0224D01*
X0104818Y040991D02*
Y0419252D01*
X0124984Y040991D02*
Y0419252D01*
X0624496Y0245106D02*
X0631268D01*
X0678201Y0181606D02*
Y018189D01*
Y0187453D02*
Y018189D01*
X0084651Y040991D02*
Y0419252D01*
X0064484Y040991D02*
Y0419752D01*
X0697884Y0183071D02*
X07Y0185187D01*
Y0187835*
X0349705Y0064173D02*
X0351279D01*
X0351673Y0064567D02*
X0356004D01*
X0351279Y0064173D02*
X0351673Y0064567D01*
X0231102Y0087795D02*
Y0092697D01*
X0231496Y0093091*
Y0093307*
X0240945Y0092696D02*
X0241339Y0093091D01*
Y0093307*
X0240945Y0087795D02*
Y0092696D01*
X0250787Y0092303D02*
X0251575Y0093091D01*
Y0093307*
X0250787Y0087795D02*
Y0092303D01*
X0290158Y0087795D02*
Y0093091D01*
X0290551Y0093484D02*
Y0093701D01*
X0290158Y0093091D02*
X0290551Y0093484D01*
X0266535Y0103739D02*
Y011063D01*
D01*
X0250787Y0103739D02*
Y0109981D01*
X0251181Y0110374*
Y0110591*
X0240945Y0103739D02*
Y010374D01*
Y011063*
X0231102Y0103739D02*
Y011063D01*
X0600394Y0233504D02*
X0600449Y0233449D01*
X0606484*
X0606665Y0238583D02*
X0609055D01*
X0606484Y0238764D02*
X0606665Y0238583D01*
X0609055D02*
X0609842Y0237795D01*
Y0235039D02*
Y0237795D01*
Y0235039D02*
X0610776Y0234106D01*
X061574*
X0693984Y0193264D02*
X0699996D01*
X07Y0193268*
X0693744Y0188189D02*
X0693984Y0187949D01*
X0690945Y0188189D02*
X0693744D01*
X0689764Y018937D02*
X0690945Y0188189D01*
X0689764Y018937D02*
Y0192126D01*
X0688784Y0193106D02*
X0689764Y0192126D01*
X0683228Y0193106D02*
X0688784D01*
X0659449Y0161024D02*
X0663146D01*
X0663228Y0161106*
X0659449Y0167323D02*
X0663012D01*
X0663228Y0167106*
X0680472Y0188106D02*
X0683228D01*
X0177648Y0153614D02*
X0177655Y0153621D01*
X0305512Y0015926D02*
Y0057382D01*
Y0015926D02*
X0305709Y001573D01*
X025059Y001378D02*
X0250787Y0013976D01*
Y0027165*
X0253937Y0030315D02*
Y0042913D01*
X0250787Y0027165D02*
X0253937Y0030315D01*
X0250394Y0046457D02*
X0253937Y0042913D01*
X0250394Y0046457D02*
Y0057382D01*
X0305787Y0013056D02*
X0305984Y0013253D01*
X0667984Y0233929D02*
Y0242012D01*
X0664311Y0230256D02*
X0667984Y0233929D01*
X0646984Y0230256D02*
X0664311D01*
X0643563D02*
X0646984D01*
X0639713Y0234106D02*
X0643563Y0230256D01*
X0635228Y0234106D02*
X0639713D01*
X0678854Y0188106D02*
X0680472D01*
X0678201Y0187453D02*
X0678854Y0188106D01*
X0689701Y0181606D02*
Y018648D01*
X0688075Y0188106D02*
X0689701Y018648D01*
X0683228Y0188106D02*
X0688075D01*
X0063897Y0401294D02*
Y040389D01*
X0124397Y0401594D02*
Y040389D01*
X010423Y040146D02*
Y040389D01*
X0084064Y0401327D02*
Y040389D01*
X0063897Y0409323D02*
X0064484Y040991D01*
X0084064Y0409323D02*
X0084651Y040991D01*
X0305315Y0057185D02*
X0305512Y0057382D01*
X0623484Y0218323D02*
Y0224118D01*
X0618496Y0229106D02*
X0623484Y0224118D01*
X061574Y0229106D02*
X0618496D01*
X0680472Y0188106D02*
X0683228D01*
X0612284Y024339D02*
X0612835D01*
X0613853Y0242372*
Y0241821D02*
Y0242372D01*
Y0241821D02*
X0614714Y024096D01*
Y0239828D02*
Y024096D01*
Y0239828D02*
X0615436Y0239106D01*
X061574*
X0618496*
X0624496Y0245106*
X020161Y0395106D02*
X020211Y0394606D01*
X0170276Y0371063D02*
X017126D01*
X0683228Y0203106D02*
X0683613D01*
X0684335Y0203828*
X0674984Y0203594D02*
Y020889D01*
Y0203594D02*
X0680472Y0198106D01*
X0683228*
X0648161Y0195457D02*
X0651984D01*
X0636905Y0184201D02*
X0648161Y0195457D01*
X0631984Y0184201D02*
X0636905D01*
X0654236Y0193106D02*
X066374D01*
X0651984Y0195358D02*
X0654236Y0193106D01*
X0651984Y0195358D02*
Y0195457D01*
X0653335Y0203106D02*
X066374D01*
X0651984Y0201756D02*
X0653335Y0203106D01*
X0606484Y0234413D02*
X0606791Y0234106D01*
X0615634Y0224D02*
X061574Y0224106D01*
X0635228D02*
X0646835D01*
X0646984Y0223957*
X010423Y0409323D02*
X0104818Y040991D01*
X0124397Y0409323D02*
X0124984Y040991D01*
G54D113*
X068229Y0177606D02*
D01*
X0682429Y017761*
X0682568Y0177625*
X0682705Y0177649*
X0682841Y0177683*
X0682974Y0177726*
X0683103Y0177778*
X0683228Y017784*
X0683349Y0177909*
X0683465Y0177987*
X0683575Y0178073*
X0683679Y0178167*
X0683701Y0178189*
X0297465Y0022474D02*
D01*
X029746Y0022613*
X0297445Y0022752*
X0297421Y0022889*
X0297387Y0023025*
X0297344Y0023158*
X0297292Y0023287*
X029723Y0023412*
X0297161Y0023533*
X0297083Y0023649*
X0296997Y0023759*
X0296971Y002379*
X0246732Y0021731D02*
D01*
X0246727Y002187*
X0246712Y0022009*
X0246688Y0022146*
X0246654Y0022282*
X0246611Y0022415*
X0246559Y0022544*
X0246497Y0022669*
X0246428Y002279*
X024635Y0022906*
X0246264Y0023016*
X024617Y002312*
X024607Y0023217*
X0245963Y0023307*
X0245934Y0023329*
X0630429Y0273508D02*
Y0277051D01*
Y0273508D02*
X0631496Y0272441D01*
X0286417Y0338583D02*
X0294094D01*
X0286319Y0338484D02*
X0286417Y0338583D01*
X0249902Y0283563D02*
X0249938Y0283527D01*
X0244282Y0283563D02*
X0249902D01*
X024311Y0282391D02*
X0244282Y0283563D01*
X024311Y0278543D02*
Y0282391D01*
X0237205Y0278543D02*
X024311D01*
X0525559Y0292158D02*
X0530461D01*
X0532186Y0290433D02*
X0535433D01*
X0525394Y0292323D02*
Y0298031D01*
X0525591Y0298228*
X0530461Y0292158D02*
X0532186Y0290433D01*
X0525394Y0292323D02*
X0525559Y0292158D01*
X0493484Y028998D02*
X0494095Y028937D01*
X0499803D02*
X05Y0289173D01*
X0494095Y028937D02*
X0499803D01*
X0483661Y028998D02*
X0493484D01*
X0295276Y0339764D02*
X0303937D01*
X0294094Y0338583D02*
X0295276Y0339764D01*
X0303937D02*
X0304134Y0339567D01*
X0207283Y001378D02*
Y0025984D01*
X0201969Y0062992D02*
X021063D01*
X0201969D02*
D01*
X0201205Y0062228D02*
X0201969Y0062992D01*
X065748Y0208661D02*
X0665083D01*
X0666655Y0210234*
X0622047Y0206693D02*
X0623484Y020813D01*
X0629313Y0218128D02*
X0633484D01*
X0623484Y020813D02*
Y021289D01*
X0623902Y0213307D02*
X0626496D01*
X062815Y0214961D02*
Y0219291D01*
X0623484Y021289D02*
X0623902Y0213307D01*
X0626496D02*
X062815Y0214961D01*
X0194905Y0062228D02*
X0201205D01*
X0194488Y0061811D02*
X0194905Y0062228D01*
X019352Y0067661D02*
X0194688D01*
X019352D02*
X0193848Y0067333D01*
X01944*
X0185915D02*
X0193848D01*
X01944D02*
X0194488Y0067244D01*
X0185827Y0067421D02*
X0185915Y0067333D01*
X0191549Y0011171D02*
Y0024476D01*
Y0011171D02*
X0191614Y0011106D01*
X0627559Y028937D02*
Y0295276D01*
X0613961Y0286722D02*
X0615132Y0287894D01*
X0613961Y0286598D02*
Y0286722D01*
X0615132Y0287894D02*
X0619291D01*
X0613543Y0286181D02*
X0613961Y0286598D01*
X0612992Y0286181D02*
X0613543D01*
X0619341Y0282234D02*
X062751D01*
X0619291Y0282185D02*
X0619341Y0282234D01*
X062751D02*
X0627559Y0282283D01*
X0270669Y0319685D02*
X0271063Y0320079D01*
X0276772*
X0159941Y0362795D02*
X0159957Y0362811D01*
X0261811Y0321457D02*
X0262205Y032185D01*
X0266732*
X0267831Y0320752*
X0269602D02*
X0270669Y0319685D01*
X0267831Y0320752D02*
X0269602D01*
X0255906Y0326772D02*
Y0336614D01*
Y0326772D02*
X0261221Y0321457D01*
X0261811*
X024628Y0338583D02*
X0253937D01*
X0255906Y0336614*
X0263878Y0338484D02*
X0286319D01*
X0263779Y0338583D02*
X0263878Y0338484D01*
X036266Y007277D02*
X0370506D01*
X0370669Y0072933*
X0362006Y0072116D02*
X036266Y007277D01*
X0683701Y0178189D02*
X0683858Y0178347D01*
X0683701Y0178189D02*
D01*
X066874Y0177606D02*
X068229D01*
X0297465Y0014149D02*
Y0022474D01*
D01*
X0309744Y0011126D02*
Y0025197D01*
X0279921D02*
X0281766Y0023352D01*
X0270354Y0011106D02*
Y0017956D01*
X0246732Y0021731D02*
D01*
X0254545Y0011167D02*
Y0024423D01*
X0246732Y0021731D02*
D01*
Y0011106D02*
Y0021731D01*
X0234756Y0011271D02*
Y0023708D01*
X0203425Y0011106D02*
Y0024547D01*
X0208465Y0027165D02*
X0211221D01*
X0187677Y0011106D02*
Y0024089D01*
X018374Y0025538D02*
X0184984Y0026782D01*
X0183578Y00257D02*
X018466Y0026782D01*
X0181507Y00257D02*
X0183578D01*
X018374Y0011106D02*
Y0025538D01*
X0179803Y0011106D02*
Y0023996D01*
X0279999Y0025197D02*
X028376D01*
X0279921D02*
X0279999D01*
X0362006Y0065057D02*
Y0072116D01*
X0361516Y0064567D02*
X0362006Y0065057D01*
X0636221Y028937D02*
Y0295276D01*
X0619685Y0248425D02*
X0624803Y0253543D01*
X0612284Y0248823D02*
X0618963D01*
X061936Y0248425D02*
X0619685D01*
X0624803Y0253543D02*
X0631496D01*
X0618963Y0248823D02*
X061936Y0248425D01*
X0631299Y0253346D02*
X0631496Y0253543D01*
Y0253642D02*
Y026063D01*
Y0267323*
Y0272441*
X0627953Y0279528D02*
X0630429Y0277051D01*
X0627953Y0279528D02*
Y028189D01*
X0627559Y0282283D02*
X0627953Y028189D01*
X0636221Y0282283D02*
X0646063D01*
X0627559D02*
X0636221D01*
X0646063D02*
X0649213Y0279134D01*
X066874Y0172106D02*
Y0177606D01*
Y0167106D02*
Y0172106D01*
Y0161106D02*
Y0167106D01*
Y0161106D02*
X0669291Y0160555D01*
Y0153842D02*
X0670028Y0153106D01*
X0669291Y0153842D02*
Y0160555D01*
X0670028Y0142106D02*
Y0153106D01*
X0683858Y0164961D02*
Y0178347D01*
X0684268Y0178756*
Y0181606*
X0295747Y0025197D02*
X0296971Y002379D01*
X0244706Y0024259D02*
X0245934Y0023329D01*
X0309724Y0011106D02*
X0309744Y0011126D01*
X0263687Y0024791D02*
X0269079D01*
X0263773Y0024705D02*
X0265167D01*
X0263687Y0024791D02*
X0263773Y0024705D01*
X0270251Y001806D02*
X0270354Y0017956D01*
X0269079Y0024791D02*
X0270251Y0023619D01*
X0297465Y0014149D02*
X0297834Y001378D01*
X0254545Y0024423D02*
X0254606Y0024484D01*
X0285654Y0014149D02*
Y0023303D01*
X0234756Y0011271D02*
X0234921Y0011106D01*
X028376Y0025197D02*
X0285654Y0023303D01*
X0281766Y00141D02*
X0282086Y001378D01*
X0281766Y00141D02*
Y0023352D01*
X0233858Y0024606D02*
X0234756Y0023708D01*
X0265167Y0024705D02*
X0266338Y0023533D01*
X0270251Y0013805D02*
X0270275Y001378D01*
X0270251Y0013805D02*
Y001806D01*
X0266338Y001378D02*
Y0023533D01*
X0203425Y0024547D02*
X0203484Y0024606D01*
X0230984D02*
X0233858D01*
X0285654Y0014149D02*
X0286023Y001378D01*
X0270251Y001806D02*
Y0023619D01*
X0207362Y0011106D02*
X020767Y0011414D01*
X0207283Y0025984D02*
X0208465Y0027165D01*
X018466Y0026782D02*
X0184984D01*
X0179803Y0023996D02*
X0181507Y00257D01*
X0636417Y0133071D02*
X0666732D01*
X0631984Y0137504D02*
X0636417Y0133071D01*
X0631984Y0137504D02*
Y0146012D01*
X0670028Y0136366D02*
Y0142106D01*
X0666732Y0133071D02*
X0670028Y0136366D01*
X0671216Y0200153D02*
Y0211405D01*
X0669169Y0198106D02*
X0671216Y0200153D01*
X066374Y0198106D02*
X0669169D01*
X0671216Y0213539D02*
X0672Y0214323D01*
X0671216Y0211405D02*
Y0213539D01*
X0670044Y0210234D02*
X0671216Y0211405D01*
X0666655Y0210234D02*
X0670044D01*
X0672Y0214323D02*
X0674984D01*
X062815Y0219291D02*
X0629313Y0218128D01*
X062815Y0219291D02*
Y0227165D01*
X0630091Y0229106*
X0635228*
X0649213Y0279134D02*
X0666917D01*
X0667984Y0280201*
G54D114*
X0052689Y0201213D02*
Y0207306D01*
X05Y0289173D02*
Y0295276D01*
X0171063Y0366043D02*
Y0370866D01*
X017126Y0371063*
X0168799Y0363779D02*
X0171063Y0366043D01*
X0168799Y0360236D02*
Y0363779D01*
X0181102Y0366929D02*
X018248Y0365551D01*
X0181102Y0366929D02*
Y0371063D01*
X0184646Y0365551D02*
X0187008Y0363189D01*
X018248Y0365551D02*
X0184646D01*
X0187008Y0360236D02*
Y0363189D01*
X0201772Y0365846D02*
Y0371063D01*
Y0365846D02*
X0204724Y0362894D01*
Y0360236D02*
Y0362894D01*
X0151378Y0360531D02*
Y0367815D01*
X0151083Y0360236D02*
X0151378Y0360531D01*
Y0367815D02*
X0154626Y0371063D01*
X0161417*
X020161Y0379098D02*
Y0395106D01*
Y0379098D02*
X0201772Y0378937D01*
X0181102D02*
X018161Y0379445D01*
Y0395106*
X017161Y0379287D02*
Y0395106D01*
X017126Y0378937D02*
X017161Y0379287D01*
X0161417Y0378937D02*
X016161Y037913D01*
Y0395106*
X0052559Y0253839D02*
X0052601Y0253881D01*
Y0259389*
X0052689Y0236506D02*
Y0242094D01*
X0052559Y0242224D02*
X0052689Y0242094D01*
X0052559Y0201083D02*
X0052689Y0201213D01*
X0052559Y0189469D02*
X0052689Y0189339D01*
Y0183906D02*
Y0189339D01*
X0052589Y0149144D02*
Y0155106D01*
X0052559Y0149114D02*
X0052589Y0149144D01*
X0052559Y01375D02*
X0052689Y013737D01*
Y0131406D02*
Y013737D01*
X0052559Y0096358D02*
X0052789Y0096588D01*
Y0102806*
X0052689Y0079006D02*
Y0084614D01*
X0052559Y0084744D02*
X0052689Y0084614D01*
G54D115*
X0212598Y0058563D03*
G54D116*
X0185827Y0041929D03*
G54D117*
X021123Y0026969D03*
G54D118*
X0183612Y0026919D03*
G54D119*
X019661Y040861D03*
X016661D03*
G54D120*
X0430778Y0258465D03*
X0418966D03*
X0407156D03*
X0398888Y0087992D03*
Y0247835D03*
X055873D03*
Y0167913D03*
Y0087992D03*
G54D121*
X0513622Y0426181D03*
G54D122*
X0523622Y0426181D03*
X0533622D03*
X0543622D03*
G54D123*
X0299014Y024384D03*
X0357136Y0209705D03*
Y0130965D03*
X0220274Y024384D03*
X0169644Y013097D03*
Y020971D03*
X0220275Y0095846D03*
X0299015D03*
G54D124*
X0019984Y0248106D03*
Y0090606D03*
Y0143106D03*
Y0195606D03*
G54D125*
X0028543Y0415206D03*
Y0036811D03*
G54D126*
X0045276Y0112205D03*
Y0121063D03*
X004626Y0227362D03*
Y0218504D03*
X0052689Y0207306D03*
X0107283Y0169291D03*
X0112205Y0117126D03*
X0101378Y0161417D03*
X0505905Y0416339D03*
X0338583Y0208661D03*
X0276772Y0320079D03*
X0270669Y0309087D03*
X0261811Y0309055D03*
X0249938Y0283527D03*
X0350394Y0303118D03*
X0356299D03*
X0366142D03*
X024311Y0267748D03*
X0244882Y0260236D03*
X0252953Y0229134D03*
X0248107D03*
X0237205Y0267717D03*
X0525591Y0298228D03*
X025889Y0242126D03*
X0525591Y0271654D03*
X0512795Y0279528D03*
Y028248D03*
X0519685Y0298228D03*
X0490158Y0270638D03*
X0505905Y0283465D03*
X05Y0295276D03*
X0279528Y0284449D03*
X0202756Y0409449D03*
X0302165Y0332677D03*
X0286417Y0327756D03*
X0288059Y0241869D03*
X0240158Y0242126D03*
X0160433Y0409449D03*
X0217488Y0357695D03*
X0201772Y0076772D03*
X0216535Y0068898D03*
X0595472Y0145669D03*
Y0141732D03*
X0597441Y0145669D03*
Y0141732D03*
X0595472Y0143701D03*
X0597441D03*
X0311024Y0281496D03*
Y0283465D03*
Y0285433D03*
X0331693Y0269685D03*
X0343504D03*
X0357185Y0272736D03*
X0312894Y0273721D03*
X0343504Y027559D03*
X0371477Y0289616D03*
X0304134Y0339567D03*
X0290158Y011063D03*
X0285039D03*
X027874D03*
X0272835D03*
X0207677Y002874D03*
Y0025591D03*
X0207087Y0037795D03*
X0209646Y0054134D03*
Y0056102D03*
X0211614Y0054134D03*
Y0056102D03*
X0213583Y0054134D03*
Y0056102D03*
X065748Y0208661D03*
X0620079Y019685D03*
Y0198819D03*
Y0200787D03*
X0622047Y019685D03*
Y0198819D03*
Y0200787D03*
Y0206693D03*
X0191614Y0024476D03*
X0627559Y0295276D03*
X0612992Y0276772D03*
X0667108Y0314014D03*
Y0315982D03*
X0663171Y0314014D03*
Y0315982D03*
X066514D03*
Y0314014D03*
X0272638Y0229331D03*
X0238189Y0354331D03*
X0271654Y0346457D03*
Y0354331D03*
Y0362205D03*
X0238189Y0346457D03*
Y0362205D03*
X0134843Y0151575D03*
X0107283Y0177165D03*
Y0231299D03*
X0101181Y0110433D03*
X011811Y0184055D03*
Y0237205D03*
X0120079Y0200787D03*
Y0253937D03*
X0163957Y035748D03*
X0181727D03*
X0199803Y0357283D03*
X021752Y0363189D03*
X0199803D03*
X0181794Y0362897D03*
X0163992Y0362811D03*
X0181102Y0409449D03*
X0173228D03*
X0064961Y0430118D03*
X0084646D03*
X0104331D03*
X0125D03*
X0288059Y0246457D03*
X0320866Y0293307D03*
X030115Y0291307D03*
X0329918Y0292362D03*
X0324803Y0293276D03*
X0362205Y0281496D03*
X0362156Y0278592D03*
X0294341Y0291289D03*
X025889Y0246457D03*
X0258858Y0262795D03*
X0293069Y0257983D03*
X0298031Y0260531D03*
X0290059Y026063D03*
X0247638Y0260236D03*
X0229035Y0246555D03*
X0293307Y021752D03*
X0289923D03*
X0331802Y0166952D03*
X0386372Y0163466D03*
X0354331Y0171291D03*
X0373031Y0167291D03*
X0360236Y0171291D03*
X0280512Y0229331D03*
X0523228Y0281496D03*
Y0273622D03*
X0286024Y0229232D03*
X029813D03*
X0268437Y0241831D03*
X0268701Y0246457D03*
X0245674Y0228738D03*
X0373031Y0208661D03*
Y0206693D03*
Y0204724D03*
Y0202756D03*
Y0188976D03*
Y0180118D03*
Y0177165D03*
X0354331Y0141732D03*
X0360236D03*
Y0151575D03*
X0354331D03*
Y0161417D03*
X0360236D03*
X0354331Y0181102D03*
X0360236D03*
X0354331Y0190945D03*
X0360236D03*
Y0200787D03*
X0354331D03*
X0338583Y0204724D03*
Y0202756D03*
Y0206693D03*
X0228051Y0260039D03*
X0184144Y0210148D03*
X0164961Y023002D03*
X0166437Y0233661D03*
X0184429Y0207604D03*
X0124397Y0401594D03*
X010423Y040146D03*
X0084064Y0401327D03*
X0063897Y0401294D03*
X0341142Y0142421D03*
Y0139272D03*
X0341283Y0136314D03*
X0341397Y0133917D03*
X0188944Y0151607D03*
X0240613Y0229269D03*
X0167484Y0198906D03*
X011998Y0250197D03*
X0119685Y0196752D03*
X011939Y0143504D03*
X0119587Y0091437D03*
X0278248Y0241831D03*
X0266437Y0229134D03*
X0262598D03*
X0259547Y0229035D03*
X0255906Y0229134D03*
X0248819Y0241831D03*
X0243307Y0229134D03*
X0233563Y0229035D03*
X0231004D03*
X023002Y024187D03*
X0278543Y0246457D03*
X0239173D03*
X024941D03*
X0492913Y0274803D03*
X0564921Y0290394D03*
X0570866Y0285433D03*
X0401575Y015748D03*
X0449803Y028937D03*
Y0284449D03*
X0397899Y0165616D03*
X0401575Y0168307D03*
X0401533Y0172321D03*
X0386371Y017815D03*
X0386433Y0160893D03*
X0386458Y0157787D03*
X0401461Y0175652D03*
X0401575Y017815D03*
Y0165354D03*
Y0162833D03*
Y0160433D03*
X0564961Y0280512D03*
X0564921Y0275551D03*
X0171884Y0149606D03*
X0167184D03*
X0149606Y0151575D03*
X0697884Y0183071D03*
X0231496Y0093307D03*
X0241339D03*
X0251575D03*
X0290551Y0093701D03*
X0266535Y011063D03*
X0261024D03*
X0251181Y0110591D03*
X0240945Y011063D03*
X0231102D03*
X0172184Y0168571D03*
X0167084D03*
X0636221Y0295276D03*
X0645084Y0246263D03*
Y0253543D03*
X0645276Y026063D03*
X0645182Y0267323D03*
X0645084Y0274016D03*
X065878Y0152931D03*
X0659449Y0167323D03*
Y0161024D03*
Y0177559D03*
Y0172047D03*
X0349705Y0064173D03*
X0270866Y0097638D03*
X0171484Y0159506D03*
X0260668Y009319D03*
X0276772Y0097638D03*
X0279921D03*
X0275984Y0079528D03*
X0274016Y0097638D03*
X0282677Y0079528D03*
X0262598D03*
X028937D03*
X0273228D03*
X0171884Y0179206D03*
X0167584Y0189106D03*
X0282677Y0097638D03*
X0269291Y0079528D03*
X0259842D03*
X026811Y0097638D03*
X0264961D03*
X0262205D03*
X0167184Y0179206D03*
X0266535Y0079528D03*
X0167184Y0139906D03*
X0279921Y0079528D03*
X0167084Y0159506D03*
X0286221Y0079528D03*
X0171684Y0139906D03*
X0172184Y0198906D03*
Y0189006D03*
X0251181Y0040551D03*
X0261024Y0027953D03*
X0257874D03*
X0298046Y0040915D03*
X0282198Y0040785D03*
X0274882Y0028231D03*
X0246988Y0041099D03*
X0290549Y0027951D03*
X0287828Y002496D03*
X0285433Y0040551D03*
X0277953Y0027953D03*
X0266535Y0040551D03*
X0270472D03*
X0235039D03*
X0238976D03*
X0293701Y0027953D03*
X0295747Y0025197D03*
X0301969Y0040551D03*
X0244706Y0024259D03*
X0241339Y0027953D03*
X0244488D03*
X0263687Y0024791D03*
X0279999Y0025197D03*
X0254606Y0024484D03*
X0309744Y0025197D03*
X0203484Y0024606D03*
X0230984D03*
X0662884Y0137206D03*
X0211221Y002874D03*
X0215158D03*
X0211221Y0025591D03*
X0215158D03*
X0183268D03*
X0185236D03*
X0187205D03*
X0183268Y002874D03*
X0185236D03*
X0187205D03*
X0349853Y0068206D03*
X0669478Y018309D03*
X0669984Y0188106D03*
X0694984Y0209506D03*
X0660784Y0217606D03*
X0639584Y0211106D03*
X0604884Y0217106D03*
X0600394Y0243021D03*
X0627484Y0239106D03*
X0052689Y0079006D03*
X0052789Y0102806D03*
X0052689Y0131406D03*
X0052589Y0155106D03*
X0052689Y0183906D03*
Y0236506D03*
X0052601Y0259389D03*
G54D127*
X0244124Y0317303D03*
X0482313Y0419665D03*
Y0317303D03*
X0244124Y0419665D03*
G54D128*
X0370669Y0072933D03*
G54D129*
X0619685Y0248425D03*
X0683858Y0164961D03*
M02*